FILE_TYPE = MACRO_DRAWING;
SET COLOR_WIRE YELLOW;
SET COLOR_PROP MONO;
SET COLOR_DOT WHITE;
SET COLOR_ARC YELLOW;
SET COLOR_BODY GREEN;
SET COLOR_NOTE MONO;
SET PROP_DISPLAY VALUE;
SET PAGE_NUMBER P23;
FORCEADD OFFPAGE..6
(-6450 1500);
FORCEPROP 2 LAST $XR1 44 
J 0
(-6789 1500);
DISPLAY 0.638298 (-6789 1500);
PAINT MONO (-6789 1500);
FORCEPROP 2 LAST $XR0 43 
J 0
(-6699 1500);
DISPLAY 0.638298 (-6699 1500);
PAINT MONO (-6699 1500);
FORCEPROP 2 LAST CDS_LIB mstr_standard
J 0
(-6450 1500);
PAINT MONO (-6450 1500);
DISPLAY INVISIBLE (-6450 1500);
FORCEPROP 2 LAST PATH I1
J 0
(-6400 1575);
DISPLAY 1.021277 (-6400 1575);
PAINT ORANGE (-6400 1575);
DISPLAY INVISIBLE (-6400 1575);
FORCEPROP 1 LAST OFFPAGE TRUE
J 0
(-6125 1375);
DISPLAY 1.170213 (-6125 1375);
PAINT GREEN (-6125 1375);
DISPLAY INVISIBLE (-6125 1375);
FORCEPROP 1 LAST COMMENT_BODY TRUE
J 0
(-6350 1425);
DISPLAY 1.170213 (-6350 1425);
PAINT GREEN (-6350 1425);
DISPLAY INVISIBLE (-6350 1425);
FORCEADD TAP..6
(-5600 850);
FORCEPROP 3 LASTPIN (-5550 850) SIG_NAME M_A_CLK_DP<0>
J 0
(-5540 860);
DISPLAY 0.659574 (-5540 860);
PAINT MONO (-5540 860);
DISPLAY INVISIBLE (-5540 860);
FORCEPROP 1 LASTPIN (-5550 850) BN 0
J 0
(-5602 858);
DISPLAY 0.617021 (-5602 858);
PAINT PINK (-5602 858);
FORCEPROP 2 LAST CDS_LIB mstr_standard
J 0
(-5600 850);
PAINT MONO (-5600 850);
DISPLAY INVISIBLE (-5600 850);
FORCEPROP 1 LAST PATH I10
J 0
(-5602 850);
DISPLAY 0.872340 (-5602 850);
PAINT GREEN (-5602 850);
DISPLAY INVISIBLE (-5602 850);
FORCEPROP 1 LAST BODY_TYPE PLUMBING
J 0
(-5600 800);
DISPLAY 1.595745 (-5600 800);
PAINT GREEN (-5600 800);
DISPLAY INVISIBLE (-5600 800);
FORCEPROP 1 LAST HDL_TAP TRUE
J 0
(-5275 725);
DISPLAY 1.595745 (-5275 725);
PAINT GREEN (-5275 725);
DISPLAY INVISIBLE (-5275 725);
FORCEADD TAP..6
R 2
(-2875 1600);
FORCEPROP 3 LASTPIN (-2925 1600) SIG_NAME M_A_ODT<3>
J 0
(-2915 1610);
DISPLAY 0.659574 (-2915 1610);
PAINT MONO (-2915 1610);
DISPLAY INVISIBLE (-2915 1610);
FORCEPROP 1 LASTPIN (-2925 1600) BN 3
J 2
(-2873 1608);
DISPLAY 0.617021 (-2873 1608);
PAINT PINK (-2873 1608);
FORCEPROP 2 LAST CDS_LIB mstr_standard
J 0
(-2875 1600);
PAINT MONO (-2875 1600);
DISPLAY INVISIBLE (-2875 1600);
FORCEPROP 1 LAST PATH I100
J 2
(-2873 1600);
DISPLAY 0.872340 (-2873 1600);
PAINT GREEN (-2873 1600);
DISPLAY INVISIBLE (-2873 1600);
FORCEPROP 1 LAST BODY_TYPE PLUMBING
J 2
(-2875 1550);
DISPLAY 1.595745 (-2875 1550);
PAINT GREEN (-2875 1550);
DISPLAY INVISIBLE (-2875 1550);
FORCEPROP 1 LAST HDL_TAP TRUE
J 2
(-3200 1475);
DISPLAY 1.595745 (-3200 1475);
PAINT GREEN (-3200 1475);
DISPLAY INVISIBLE (-3200 1475);
FORCEADD TAP..6
R 2
(-2875 1700);
FORCEPROP 3 LASTPIN (-2925 1700) SIG_NAME M_A_CKE<0>
J 0
(-2915 1710);
DISPLAY 0.659574 (-2915 1710);
PAINT MONO (-2915 1710);
DISPLAY INVISIBLE (-2915 1710);
FORCEPROP 1 LASTPIN (-2925 1700) BN 0
J 2
(-2873 1708);
DISPLAY 0.617021 (-2873 1708);
PAINT PINK (-2873 1708);
FORCEPROP 2 LAST CDS_LIB mstr_standard
J 0
(-2875 1700);
PAINT MONO (-2875 1700);
DISPLAY INVISIBLE (-2875 1700);
FORCEPROP 1 LAST PATH I101
J 2
(-2873 1700);
DISPLAY 0.872340 (-2873 1700);
PAINT GREEN (-2873 1700);
DISPLAY INVISIBLE (-2873 1700);
FORCEPROP 1 LAST BODY_TYPE PLUMBING
J 2
(-2875 1650);
DISPLAY 1.595745 (-2875 1650);
PAINT GREEN (-2875 1650);
DISPLAY INVISIBLE (-2875 1650);
FORCEPROP 1 LAST HDL_TAP TRUE
J 2
(-3200 1575);
DISPLAY 1.595745 (-3200 1575);
PAINT GREEN (-3200 1575);
DISPLAY INVISIBLE (-3200 1575);
FORCEADD TAP..6
R 2
(-2875 1550);
FORCEPROP 3 LASTPIN (-2925 1550) SIG_NAME M_A_ODT<2>
J 0
(-2915 1560);
DISPLAY 0.659574 (-2915 1560);
PAINT MONO (-2915 1560);
DISPLAY INVISIBLE (-2915 1560);
FORCEPROP 1 LASTPIN (-2925 1550) BN 2
J 2
(-2873 1558);
DISPLAY 0.617021 (-2873 1558);
PAINT PINK (-2873 1558);
FORCEPROP 2 LAST CDS_LIB mstr_standard
J 0
(-2875 1550);
PAINT MONO (-2875 1550);
DISPLAY INVISIBLE (-2875 1550);
FORCEPROP 1 LAST PATH I102
J 2
(-2873 1550);
DISPLAY 0.872340 (-2873 1550);
PAINT GREEN (-2873 1550);
DISPLAY INVISIBLE (-2873 1550);
FORCEPROP 1 LAST BODY_TYPE PLUMBING
J 2
(-2875 1500);
DISPLAY 1.595745 (-2875 1500);
PAINT GREEN (-2875 1500);
DISPLAY INVISIBLE (-2875 1500);
FORCEPROP 1 LAST HDL_TAP TRUE
J 2
(-3200 1425);
DISPLAY 1.595745 (-3200 1425);
PAINT GREEN (-3200 1425);
DISPLAY INVISIBLE (-3200 1425);
FORCEADD TAP..6
R 2
(-2875 1500);
FORCEPROP 3 LASTPIN (-2925 1500) SIG_NAME M_A_ODT<1>
J 0
(-2915 1510);
DISPLAY 0.659574 (-2915 1510);
PAINT MONO (-2915 1510);
DISPLAY INVISIBLE (-2915 1510);
FORCEPROP 1 LASTPIN (-2925 1500) BN 1
J 2
(-2873 1508);
DISPLAY 0.617021 (-2873 1508);
PAINT PINK (-2873 1508);
FORCEPROP 2 LAST CDS_LIB mstr_standard
J 0
(-2875 1500);
PAINT MONO (-2875 1500);
DISPLAY INVISIBLE (-2875 1500);
FORCEPROP 1 LAST PATH I103
J 2
(-2873 1500);
DISPLAY 0.872340 (-2873 1500);
PAINT GREEN (-2873 1500);
DISPLAY INVISIBLE (-2873 1500);
FORCEPROP 1 LAST BODY_TYPE PLUMBING
J 2
(-2875 1450);
DISPLAY 1.595745 (-2875 1450);
PAINT GREEN (-2875 1450);
DISPLAY INVISIBLE (-2875 1450);
FORCEPROP 1 LAST HDL_TAP TRUE
J 2
(-3200 1375);
DISPLAY 1.595745 (-3200 1375);
PAINT GREEN (-3200 1375);
DISPLAY INVISIBLE (-3200 1375);
FORCEADD TAP..6
R 2
(-2875 1850);
FORCEPROP 3 LASTPIN (-2925 1850) SIG_NAME M_A_CKE<3>
J 0
(-2915 1860);
DISPLAY 0.659574 (-2915 1860);
PAINT MONO (-2915 1860);
DISPLAY INVISIBLE (-2915 1860);
FORCEPROP 1 LASTPIN (-2925 1850) BN 3
J 2
(-2873 1858);
DISPLAY 0.617021 (-2873 1858);
PAINT PINK (-2873 1858);
FORCEPROP 2 LAST CDS_LIB mstr_standard
J 0
(-2875 1850);
PAINT MONO (-2875 1850);
DISPLAY INVISIBLE (-2875 1850);
FORCEPROP 1 LAST PATH I104
J 2
(-2873 1850);
DISPLAY 0.872340 (-2873 1850);
PAINT GREEN (-2873 1850);
DISPLAY INVISIBLE (-2873 1850);
FORCEPROP 1 LAST BODY_TYPE PLUMBING
J 2
(-2875 1800);
DISPLAY 1.595745 (-2875 1800);
PAINT GREEN (-2875 1800);
DISPLAY INVISIBLE (-2875 1800);
FORCEPROP 1 LAST HDL_TAP TRUE
J 2
(-3200 1725);
DISPLAY 1.595745 (-3200 1725);
PAINT GREEN (-3200 1725);
DISPLAY INVISIBLE (-3200 1725);
FORCEADD TAP..6
R 2
(-2875 1950);
FORCEPROP 3 LASTPIN (-2925 1950) SIG_NAME M_A_MA<0>
J 0
(-2915 1960);
DISPLAY 0.659574 (-2915 1960);
PAINT MONO (-2915 1960);
DISPLAY INVISIBLE (-2915 1960);
FORCEPROP 1 LASTPIN (-2925 1950) BN 0
J 2
(-2873 1958);
DISPLAY 0.617021 (-2873 1958);
PAINT PINK (-2873 1958);
FORCEPROP 2 LAST CDS_LIB mstr_standard
J 0
(-2875 1950);
PAINT MONO (-2875 1950);
DISPLAY INVISIBLE (-2875 1950);
FORCEPROP 1 LAST PATH I105
J 2
(-2873 1950);
DISPLAY 0.872340 (-2873 1950);
PAINT GREEN (-2873 1950);
DISPLAY INVISIBLE (-2873 1950);
FORCEPROP 1 LAST BODY_TYPE PLUMBING
J 2
(-2875 1900);
DISPLAY 1.595745 (-2875 1900);
PAINT GREEN (-2875 1900);
DISPLAY INVISIBLE (-2875 1900);
FORCEPROP 1 LAST HDL_TAP TRUE
J 2
(-3200 1825);
DISPLAY 1.595745 (-3200 1825);
PAINT GREEN (-3200 1825);
DISPLAY INVISIBLE (-3200 1825);
FORCEADD TAP..6
R 2
(-2875 1800);
FORCEPROP 3 LASTPIN (-2925 1800) SIG_NAME M_A_CKE<2>
J 0
(-2915 1810);
DISPLAY 0.659574 (-2915 1810);
PAINT MONO (-2915 1810);
DISPLAY INVISIBLE (-2915 1810);
FORCEPROP 1 LASTPIN (-2925 1800) BN 2
J 2
(-2873 1808);
DISPLAY 0.617021 (-2873 1808);
PAINT PINK (-2873 1808);
FORCEPROP 2 LAST CDS_LIB mstr_standard
J 0
(-2875 1800);
PAINT MONO (-2875 1800);
DISPLAY INVISIBLE (-2875 1800);
FORCEPROP 1 LAST PATH I106
J 2
(-2873 1800);
DISPLAY 0.872340 (-2873 1800);
PAINT GREEN (-2873 1800);
DISPLAY INVISIBLE (-2873 1800);
FORCEPROP 1 LAST BODY_TYPE PLUMBING
J 2
(-2875 1750);
DISPLAY 1.595745 (-2875 1750);
PAINT GREEN (-2875 1750);
DISPLAY INVISIBLE (-2875 1750);
FORCEPROP 1 LAST HDL_TAP TRUE
J 2
(-3200 1675);
DISPLAY 1.595745 (-3200 1675);
PAINT GREEN (-3200 1675);
DISPLAY INVISIBLE (-3200 1675);
FORCEADD TAP..6
R 2
(-2875 1750);
FORCEPROP 3 LASTPIN (-2925 1750) SIG_NAME M_A_CKE<1>
J 0
(-2915 1760);
DISPLAY 0.659574 (-2915 1760);
PAINT MONO (-2915 1760);
DISPLAY INVISIBLE (-2915 1760);
FORCEPROP 1 LASTPIN (-2925 1750) BN 1
J 2
(-2873 1758);
DISPLAY 0.617021 (-2873 1758);
PAINT PINK (-2873 1758);
FORCEPROP 2 LAST CDS_LIB mstr_standard
J 0
(-2875 1750);
PAINT MONO (-2875 1750);
DISPLAY INVISIBLE (-2875 1750);
FORCEPROP 1 LAST PATH I107
J 2
(-2873 1750);
DISPLAY 0.872340 (-2873 1750);
PAINT GREEN (-2873 1750);
DISPLAY INVISIBLE (-2873 1750);
FORCEPROP 1 LAST BODY_TYPE PLUMBING
J 2
(-2875 1700);
DISPLAY 1.595745 (-2875 1700);
PAINT GREEN (-2875 1700);
DISPLAY INVISIBLE (-2875 1700);
FORCEPROP 1 LAST HDL_TAP TRUE
J 2
(-3200 1625);
DISPLAY 1.595745 (-3200 1625);
PAINT GREEN (-3200 1625);
DISPLAY INVISIBLE (-3200 1625);
FORCEADD TAP..6
R 2
(-2875 2000);
FORCEPROP 3 LASTPIN (-2925 2000) SIG_NAME M_A_MA<1>
J 0
(-2915 2010);
DISPLAY 0.659574 (-2915 2010);
PAINT MONO (-2915 2010);
DISPLAY INVISIBLE (-2915 2010);
FORCEPROP 1 LASTPIN (-2925 2000) BN 1
J 2
(-2873 2008);
DISPLAY 0.617021 (-2873 2008);
PAINT PINK (-2873 2008);
FORCEPROP 2 LAST CDS_LIB mstr_standard
J 0
(-2875 2000);
PAINT MONO (-2875 2000);
DISPLAY INVISIBLE (-2875 2000);
FORCEPROP 1 LAST PATH I108
J 2
(-2873 2000);
DISPLAY 0.872340 (-2873 2000);
PAINT GREEN (-2873 2000);
DISPLAY INVISIBLE (-2873 2000);
FORCEPROP 1 LAST BODY_TYPE PLUMBING
J 2
(-2875 1950);
DISPLAY 1.595745 (-2875 1950);
PAINT GREEN (-2875 1950);
DISPLAY INVISIBLE (-2875 1950);
FORCEPROP 1 LAST HDL_TAP TRUE
J 2
(-3200 1875);
DISPLAY 1.595745 (-3200 1875);
PAINT GREEN (-3200 1875);
DISPLAY INVISIBLE (-3200 1875);
FORCEADD TAP..6
R 2
(-2875 2050);
FORCEPROP 3 LASTPIN (-2925 2050) SIG_NAME M_A_MA<2>
J 0
(-2915 2060);
DISPLAY 0.659574 (-2915 2060);
PAINT MONO (-2915 2060);
DISPLAY INVISIBLE (-2915 2060);
FORCEPROP 1 LASTPIN (-2925 2050) BN 2
J 2
(-2873 2058);
DISPLAY 0.617021 (-2873 2058);
PAINT PINK (-2873 2058);
FORCEPROP 2 LAST CDS_LIB mstr_standard
J 0
(-2875 2050);
PAINT MONO (-2875 2050);
DISPLAY INVISIBLE (-2875 2050);
FORCEPROP 1 LAST PATH I109
J 2
(-2873 2050);
DISPLAY 0.872340 (-2873 2050);
PAINT GREEN (-2873 2050);
DISPLAY INVISIBLE (-2873 2050);
FORCEPROP 1 LAST BODY_TYPE PLUMBING
J 2
(-2875 2000);
DISPLAY 1.595745 (-2875 2000);
PAINT GREEN (-2875 2000);
DISPLAY INVISIBLE (-2875 2000);
FORCEPROP 1 LAST HDL_TAP TRUE
J 2
(-3200 1925);
DISPLAY 1.595745 (-3200 1925);
PAINT GREEN (-3200 1925);
DISPLAY INVISIBLE (-3200 1925);
FORCEADD TAP..6
(-5600 950);
FORCEPROP 3 LASTPIN (-5550 950) SIG_NAME M_A_CLK_DP<2>
J 0
(-5540 960);
DISPLAY 0.659574 (-5540 960);
PAINT MONO (-5540 960);
DISPLAY INVISIBLE (-5540 960);
FORCEPROP 1 LASTPIN (-5550 950) BN 2
J 0
(-5602 958);
DISPLAY 0.617021 (-5602 958);
PAINT PINK (-5602 958);
FORCEPROP 2 LAST CDS_LIB mstr_standard
J 0
(-5600 950);
PAINT MONO (-5600 950);
DISPLAY INVISIBLE (-5600 950);
FORCEPROP 1 LAST PATH I11
J 0
(-5602 950);
DISPLAY 0.872340 (-5602 950);
PAINT GREEN (-5602 950);
DISPLAY INVISIBLE (-5602 950);
FORCEPROP 1 LAST BODY_TYPE PLUMBING
J 0
(-5600 900);
DISPLAY 1.595745 (-5600 900);
PAINT GREEN (-5600 900);
DISPLAY INVISIBLE (-5600 900);
FORCEPROP 1 LAST HDL_TAP TRUE
J 0
(-5275 825);
DISPLAY 1.595745 (-5275 825);
PAINT GREEN (-5275 825);
DISPLAY INVISIBLE (-5275 825);
FORCEADD TAP..6
R 2
(-2875 2100);
FORCEPROP 3 LASTPIN (-2925 2100) SIG_NAME M_A_MA<3>
J 0
(-2915 2110);
DISPLAY 0.659574 (-2915 2110);
PAINT MONO (-2915 2110);
DISPLAY INVISIBLE (-2915 2110);
FORCEPROP 1 LASTPIN (-2925 2100) BN 3
J 2
(-2873 2108);
DISPLAY 0.617021 (-2873 2108);
PAINT PINK (-2873 2108);
FORCEPROP 2 LAST CDS_LIB mstr_standard
J 0
(-2875 2100);
PAINT MONO (-2875 2100);
DISPLAY INVISIBLE (-2875 2100);
FORCEPROP 1 LAST PATH I110
J 2
(-2873 2100);
DISPLAY 0.872340 (-2873 2100);
PAINT GREEN (-2873 2100);
DISPLAY INVISIBLE (-2873 2100);
FORCEPROP 1 LAST BODY_TYPE PLUMBING
J 2
(-2875 2050);
DISPLAY 1.595745 (-2875 2050);
PAINT GREEN (-2875 2050);
DISPLAY INVISIBLE (-2875 2050);
FORCEPROP 1 LAST HDL_TAP TRUE
J 2
(-3200 1975);
DISPLAY 1.595745 (-3200 1975);
PAINT GREEN (-3200 1975);
DISPLAY INVISIBLE (-3200 1975);
FORCEADD TAP..6
R 2
(-2875 2250);
FORCEPROP 3 LASTPIN (-2925 2250) SIG_NAME M_A_MA<6>
J 0
(-2915 2260);
DISPLAY 0.659574 (-2915 2260);
PAINT MONO (-2915 2260);
DISPLAY INVISIBLE (-2915 2260);
FORCEPROP 1 LASTPIN (-2925 2250) BN 6
J 2
(-2873 2258);
DISPLAY 0.617021 (-2873 2258);
PAINT PINK (-2873 2258);
FORCEPROP 2 LAST CDS_LIB mstr_standard
J 0
(-2875 2250);
PAINT MONO (-2875 2250);
DISPLAY INVISIBLE (-2875 2250);
FORCEPROP 1 LAST PATH I111
J 2
(-2873 2250);
DISPLAY 0.872340 (-2873 2250);
PAINT GREEN (-2873 2250);
DISPLAY INVISIBLE (-2873 2250);
FORCEPROP 1 LAST BODY_TYPE PLUMBING
J 2
(-2875 2200);
DISPLAY 1.595745 (-2875 2200);
PAINT GREEN (-2875 2200);
DISPLAY INVISIBLE (-2875 2200);
FORCEPROP 1 LAST HDL_TAP TRUE
J 2
(-3200 2125);
DISPLAY 1.595745 (-3200 2125);
PAINT GREEN (-3200 2125);
DISPLAY INVISIBLE (-3200 2125);
FORCEADD TAP..6
R 2
(-2875 2200);
FORCEPROP 3 LASTPIN (-2925 2200) SIG_NAME M_A_MA<5>
J 0
(-2915 2210);
DISPLAY 0.659574 (-2915 2210);
PAINT MONO (-2915 2210);
DISPLAY INVISIBLE (-2915 2210);
FORCEPROP 1 LASTPIN (-2925 2200) BN 5
J 2
(-2873 2208);
DISPLAY 0.617021 (-2873 2208);
PAINT PINK (-2873 2208);
FORCEPROP 2 LAST CDS_LIB mstr_standard
J 0
(-2875 2200);
PAINT MONO (-2875 2200);
DISPLAY INVISIBLE (-2875 2200);
FORCEPROP 1 LAST PATH I112
J 2
(-2873 2200);
DISPLAY 0.872340 (-2873 2200);
PAINT GREEN (-2873 2200);
DISPLAY INVISIBLE (-2873 2200);
FORCEPROP 1 LAST BODY_TYPE PLUMBING
J 2
(-2875 2150);
DISPLAY 1.595745 (-2875 2150);
PAINT GREEN (-2875 2150);
DISPLAY INVISIBLE (-2875 2150);
FORCEPROP 1 LAST HDL_TAP TRUE
J 2
(-3200 2075);
DISPLAY 1.595745 (-3200 2075);
PAINT GREEN (-3200 2075);
DISPLAY INVISIBLE (-3200 2075);
FORCEADD TAP..6
R 2
(-2875 2150);
FORCEPROP 3 LASTPIN (-2925 2150) SIG_NAME M_A_MA<4>
J 0
(-2915 2160);
DISPLAY 0.659574 (-2915 2160);
PAINT MONO (-2915 2160);
DISPLAY INVISIBLE (-2915 2160);
FORCEPROP 1 LASTPIN (-2925 2150) BN 4
J 2
(-2873 2158);
DISPLAY 0.617021 (-2873 2158);
PAINT PINK (-2873 2158);
FORCEPROP 2 LAST CDS_LIB mstr_standard
J 0
(-2875 2150);
PAINT MONO (-2875 2150);
DISPLAY INVISIBLE (-2875 2150);
FORCEPROP 1 LAST PATH I113
J 2
(-2873 2150);
DISPLAY 0.872340 (-2873 2150);
PAINT GREEN (-2873 2150);
DISPLAY INVISIBLE (-2873 2150);
FORCEPROP 1 LAST BODY_TYPE PLUMBING
J 2
(-2875 2100);
DISPLAY 1.595745 (-2875 2100);
PAINT GREEN (-2875 2100);
DISPLAY INVISIBLE (-2875 2100);
FORCEPROP 1 LAST HDL_TAP TRUE
J 2
(-3200 2025);
DISPLAY 1.595745 (-3200 2025);
PAINT GREEN (-3200 2025);
DISPLAY INVISIBLE (-3200 2025);
FORCEADD TAP..6
R 2
(-2875 2400);
FORCEPROP 3 LASTPIN (-2925 2400) SIG_NAME M_A_MA<9>
J 0
(-2915 2410);
DISPLAY 0.659574 (-2915 2410);
PAINT MONO (-2915 2410);
DISPLAY INVISIBLE (-2915 2410);
FORCEPROP 1 LASTPIN (-2925 2400) BN 9
J 2
(-2873 2408);
DISPLAY 0.617021 (-2873 2408);
PAINT PINK (-2873 2408);
FORCEPROP 2 LAST CDS_LIB mstr_standard
J 0
(-2875 2400);
PAINT MONO (-2875 2400);
DISPLAY INVISIBLE (-2875 2400);
FORCEPROP 1 LAST PATH I114
J 2
(-2873 2400);
DISPLAY 0.872340 (-2873 2400);
PAINT GREEN (-2873 2400);
DISPLAY INVISIBLE (-2873 2400);
FORCEPROP 1 LAST BODY_TYPE PLUMBING
J 2
(-2875 2350);
DISPLAY 1.595745 (-2875 2350);
PAINT GREEN (-2875 2350);
DISPLAY INVISIBLE (-2875 2350);
FORCEPROP 1 LAST HDL_TAP TRUE
J 2
(-3200 2275);
DISPLAY 1.595745 (-3200 2275);
PAINT GREEN (-3200 2275);
DISPLAY INVISIBLE (-3200 2275);
FORCEADD TAP..6
R 2
(-2875 2450);
FORCEPROP 3 LASTPIN (-2925 2450) SIG_NAME M_A_MA<10>
J 0
(-2915 2460);
DISPLAY 0.659574 (-2915 2460);
PAINT MONO (-2915 2460);
DISPLAY INVISIBLE (-2915 2460);
FORCEPROP 1 LASTPIN (-2925 2450) BN 10
J 2
(-2873 2458);
DISPLAY 0.617021 (-2873 2458);
PAINT PINK (-2873 2458);
FORCEPROP 2 LAST CDS_LIB mstr_standard
J 0
(-2875 2450);
PAINT MONO (-2875 2450);
DISPLAY INVISIBLE (-2875 2450);
FORCEPROP 1 LAST PATH I115
J 2
(-2873 2450);
DISPLAY 0.872340 (-2873 2450);
PAINT GREEN (-2873 2450);
DISPLAY INVISIBLE (-2873 2450);
FORCEPROP 1 LAST BODY_TYPE PLUMBING
J 2
(-2875 2400);
DISPLAY 1.595745 (-2875 2400);
PAINT GREEN (-2875 2400);
DISPLAY INVISIBLE (-2875 2400);
FORCEPROP 1 LAST HDL_TAP TRUE
J 2
(-3200 2325);
DISPLAY 1.595745 (-3200 2325);
PAINT GREEN (-3200 2325);
DISPLAY INVISIBLE (-3200 2325);
FORCEADD TAP..6
R 2
(-2875 2500);
FORCEPROP 3 LASTPIN (-2925 2500) SIG_NAME M_A_MA<11>
J 0
(-2915 2510);
DISPLAY 0.659574 (-2915 2510);
PAINT MONO (-2915 2510);
DISPLAY INVISIBLE (-2915 2510);
FORCEPROP 1 LASTPIN (-2925 2500) BN 11
J 2
(-2873 2508);
DISPLAY 0.617021 (-2873 2508);
PAINT PINK (-2873 2508);
FORCEPROP 2 LAST CDS_LIB mstr_standard
J 0
(-2875 2500);
PAINT MONO (-2875 2500);
DISPLAY INVISIBLE (-2875 2500);
FORCEPROP 1 LAST PATH I116
J 2
(-2873 2500);
DISPLAY 0.872340 (-2873 2500);
PAINT GREEN (-2873 2500);
DISPLAY INVISIBLE (-2873 2500);
FORCEPROP 1 LAST BODY_TYPE PLUMBING
J 2
(-2875 2450);
DISPLAY 1.595745 (-2875 2450);
PAINT GREEN (-2875 2450);
DISPLAY INVISIBLE (-2875 2450);
FORCEPROP 1 LAST HDL_TAP TRUE
J 2
(-3200 2375);
DISPLAY 1.595745 (-3200 2375);
PAINT GREEN (-3200 2375);
DISPLAY INVISIBLE (-3200 2375);
FORCEADD TAP..6
R 2
(-2875 2350);
FORCEPROP 3 LASTPIN (-2925 2350) SIG_NAME M_A_MA<8>
J 0
(-2915 2360);
DISPLAY 0.659574 (-2915 2360);
PAINT MONO (-2915 2360);
DISPLAY INVISIBLE (-2915 2360);
FORCEPROP 1 LASTPIN (-2925 2350) BN 8
J 2
(-2873 2358);
DISPLAY 0.617021 (-2873 2358);
PAINT PINK (-2873 2358);
FORCEPROP 2 LAST CDS_LIB mstr_standard
J 0
(-2875 2350);
PAINT MONO (-2875 2350);
DISPLAY INVISIBLE (-2875 2350);
FORCEPROP 1 LAST PATH I117
J 2
(-2873 2350);
DISPLAY 0.872340 (-2873 2350);
PAINT GREEN (-2873 2350);
DISPLAY INVISIBLE (-2873 2350);
FORCEPROP 1 LAST BODY_TYPE PLUMBING
J 2
(-2875 2300);
DISPLAY 1.595745 (-2875 2300);
PAINT GREEN (-2875 2300);
DISPLAY INVISIBLE (-2875 2300);
FORCEPROP 1 LAST HDL_TAP TRUE
J 2
(-3200 2225);
DISPLAY 1.595745 (-3200 2225);
PAINT GREEN (-3200 2225);
DISPLAY INVISIBLE (-3200 2225);
FORCEADD TAP..6
R 2
(-2875 2300);
FORCEPROP 3 LASTPIN (-2925 2300) SIG_NAME M_A_MA<7>
J 0
(-2915 2310);
DISPLAY 0.659574 (-2915 2310);
PAINT MONO (-2915 2310);
DISPLAY INVISIBLE (-2915 2310);
FORCEPROP 1 LASTPIN (-2925 2300) BN 7
J 2
(-2873 2308);
DISPLAY 0.617021 (-2873 2308);
PAINT PINK (-2873 2308);
FORCEPROP 2 LAST CDS_LIB mstr_standard
J 0
(-2875 2300);
PAINT MONO (-2875 2300);
DISPLAY INVISIBLE (-2875 2300);
FORCEPROP 1 LAST PATH I118
J 2
(-2873 2300);
DISPLAY 0.872340 (-2873 2300);
PAINT GREEN (-2873 2300);
DISPLAY INVISIBLE (-2873 2300);
FORCEPROP 1 LAST BODY_TYPE PLUMBING
J 2
(-2875 2250);
DISPLAY 1.595745 (-2875 2250);
PAINT GREEN (-2875 2250);
DISPLAY INVISIBLE (-2875 2250);
FORCEPROP 1 LAST HDL_TAP TRUE
J 2
(-3200 2175);
DISPLAY 1.595745 (-3200 2175);
PAINT GREEN (-3200 2175);
DISPLAY INVISIBLE (-3200 2175);
FORCEADD TAP..6
R 2
(-2875 2650);
FORCEPROP 3 LASTPIN (-2925 2650) SIG_NAME M_A_MA<14>
J 0
(-2915 2660);
DISPLAY 0.659574 (-2915 2660);
PAINT MONO (-2915 2660);
DISPLAY INVISIBLE (-2915 2660);
FORCEPROP 1 LASTPIN (-2925 2650) BN 14
J 2
(-2873 2658);
DISPLAY 0.617021 (-2873 2658);
PAINT PINK (-2873 2658);
FORCEPROP 2 LAST CDS_LIB mstr_standard
J 0
(-2875 2650);
PAINT MONO (-2875 2650);
DISPLAY INVISIBLE (-2875 2650);
FORCEPROP 1 LAST PATH I119
J 2
(-2873 2650);
DISPLAY 0.872340 (-2873 2650);
PAINT GREEN (-2873 2650);
DISPLAY INVISIBLE (-2873 2650);
FORCEPROP 1 LAST BODY_TYPE PLUMBING
J 2
(-2875 2600);
DISPLAY 1.595745 (-2875 2600);
PAINT GREEN (-2875 2600);
DISPLAY INVISIBLE (-2875 2600);
FORCEPROP 1 LAST HDL_TAP TRUE
J 2
(-3200 2525);
DISPLAY 1.595745 (-3200 2525);
PAINT GREEN (-3200 2525);
DISPLAY INVISIBLE (-3200 2525);
FORCEADD TAP..6
(-5600 1000);
FORCEPROP 3 LASTPIN (-5550 1000) SIG_NAME M_A_CLK_DP<3>
J 0
(-5540 1010);
DISPLAY 0.659574 (-5540 1010);
PAINT MONO (-5540 1010);
DISPLAY INVISIBLE (-5540 1010);
FORCEPROP 1 LASTPIN (-5550 1000) BN 3
J 0
(-5602 1008);
DISPLAY 0.617021 (-5602 1008);
PAINT PINK (-5602 1008);
FORCEPROP 2 LAST CDS_LIB mstr_standard
J 0
(-5600 1000);
PAINT MONO (-5600 1000);
DISPLAY INVISIBLE (-5600 1000);
FORCEPROP 1 LAST PATH I12
J 0
(-5602 1000);
DISPLAY 0.872340 (-5602 1000);
PAINT GREEN (-5602 1000);
DISPLAY INVISIBLE (-5602 1000);
FORCEPROP 1 LAST BODY_TYPE PLUMBING
J 0
(-5600 950);
DISPLAY 1.595745 (-5600 950);
PAINT GREEN (-5600 950);
DISPLAY INVISIBLE (-5600 950);
FORCEPROP 1 LAST HDL_TAP TRUE
J 0
(-5275 875);
DISPLAY 1.595745 (-5275 875);
PAINT GREEN (-5275 875);
DISPLAY INVISIBLE (-5275 875);
FORCEADD TAP..6
R 2
(-2875 2700);
FORCEPROP 3 LASTPIN (-2925 2700) SIG_NAME M_A_MA<15>
J 0
(-2915 2710);
DISPLAY 0.659574 (-2915 2710);
PAINT MONO (-2915 2710);
DISPLAY INVISIBLE (-2915 2710);
FORCEPROP 1 LASTPIN (-2925 2700) BN 15
J 2
(-2873 2708);
DISPLAY 0.617021 (-2873 2708);
PAINT PINK (-2873 2708);
FORCEPROP 2 LAST CDS_LIB mstr_standard
J 0
(-2875 2700);
PAINT MONO (-2875 2700);
DISPLAY INVISIBLE (-2875 2700);
FORCEPROP 1 LAST PATH I120
J 2
(-2873 2700);
DISPLAY 0.872340 (-2873 2700);
PAINT GREEN (-2873 2700);
DISPLAY INVISIBLE (-2873 2700);
FORCEPROP 1 LAST BODY_TYPE PLUMBING
J 2
(-2875 2650);
DISPLAY 1.595745 (-2875 2650);
PAINT GREEN (-2875 2650);
DISPLAY INVISIBLE (-2875 2650);
FORCEPROP 1 LAST HDL_TAP TRUE
J 2
(-3200 2575);
DISPLAY 1.595745 (-3200 2575);
PAINT GREEN (-3200 2575);
DISPLAY INVISIBLE (-3200 2575);
FORCEADD TAP..6
R 2
(-2875 2750);
FORCEPROP 3 LASTPIN (-2925 2750) SIG_NAME M_A_MA<16>
J 0
(-2915 2760);
DISPLAY 0.659574 (-2915 2760);
PAINT MONO (-2915 2760);
DISPLAY INVISIBLE (-2915 2760);
FORCEPROP 1 LASTPIN (-2925 2750) BN 16
J 2
(-2873 2758);
DISPLAY 0.617021 (-2873 2758);
PAINT PINK (-2873 2758);
FORCEPROP 2 LAST CDS_LIB mstr_standard
J 0
(-2875 2750);
PAINT MONO (-2875 2750);
DISPLAY INVISIBLE (-2875 2750);
FORCEPROP 1 LAST PATH I121
J 2
(-2873 2750);
DISPLAY 0.872340 (-2873 2750);
PAINT GREEN (-2873 2750);
DISPLAY INVISIBLE (-2873 2750);
FORCEPROP 1 LAST BODY_TYPE PLUMBING
J 2
(-2875 2700);
DISPLAY 1.595745 (-2875 2700);
PAINT GREEN (-2875 2700);
DISPLAY INVISIBLE (-2875 2700);
FORCEPROP 1 LAST HDL_TAP TRUE
J 2
(-3200 2625);
DISPLAY 1.595745 (-3200 2625);
PAINT GREEN (-3200 2625);
DISPLAY INVISIBLE (-3200 2625);
FORCEADD TAP..6
R 2
(-2875 2600);
FORCEPROP 3 LASTPIN (-2925 2600) SIG_NAME M_A_MA<13>
J 0
(-2915 2610);
DISPLAY 0.659574 (-2915 2610);
PAINT MONO (-2915 2610);
DISPLAY INVISIBLE (-2915 2610);
FORCEPROP 1 LASTPIN (-2925 2600) BN 13
J 2
(-2873 2608);
DISPLAY 0.617021 (-2873 2608);
PAINT PINK (-2873 2608);
FORCEPROP 2 LAST CDS_LIB mstr_standard
J 0
(-2875 2600);
PAINT MONO (-2875 2600);
DISPLAY INVISIBLE (-2875 2600);
FORCEPROP 1 LAST PATH I122
J 2
(-2873 2600);
DISPLAY 0.872340 (-2873 2600);
PAINT GREEN (-2873 2600);
DISPLAY INVISIBLE (-2873 2600);
FORCEPROP 1 LAST BODY_TYPE PLUMBING
J 2
(-2875 2550);
DISPLAY 1.595745 (-2875 2550);
PAINT GREEN (-2875 2550);
DISPLAY INVISIBLE (-2875 2550);
FORCEPROP 1 LAST HDL_TAP TRUE
J 2
(-3200 2475);
DISPLAY 1.595745 (-3200 2475);
PAINT GREEN (-3200 2475);
DISPLAY INVISIBLE (-3200 2475);
FORCEADD TAP..6
R 2
(-2875 2550);
FORCEPROP 3 LASTPIN (-2925 2550) SIG_NAME M_A_MA<12>
J 0
(-2915 2560);
DISPLAY 0.659574 (-2915 2560);
PAINT MONO (-2915 2560);
DISPLAY INVISIBLE (-2915 2560);
FORCEPROP 1 LASTPIN (-2925 2550) BN 12
J 2
(-2873 2558);
DISPLAY 0.617021 (-2873 2558);
PAINT PINK (-2873 2558);
FORCEPROP 2 LAST CDS_LIB mstr_standard
J 0
(-2875 2550);
PAINT MONO (-2875 2550);
DISPLAY INVISIBLE (-2875 2550);
FORCEPROP 1 LAST PATH I123
J 2
(-2873 2550);
DISPLAY 0.872340 (-2873 2550);
PAINT GREEN (-2873 2550);
DISPLAY INVISIBLE (-2873 2550);
FORCEPROP 1 LAST BODY_TYPE PLUMBING
J 2
(-2875 2500);
DISPLAY 1.595745 (-2875 2500);
PAINT GREEN (-2875 2500);
DISPLAY INVISIBLE (-2875 2500);
FORCEPROP 1 LAST HDL_TAP TRUE
J 2
(-3200 2425);
DISPLAY 1.595745 (-3200 2425);
PAINT GREEN (-3200 2425);
DISPLAY INVISIBLE (-3200 2425);
FORCEADD TAP..6
R 2
(-2875 2900);
FORCEPROP 3 LASTPIN (-2925 2900) SIG_NAME M_A_DQS_DN<0>
J 0
(-2915 2910);
DISPLAY 0.659574 (-2915 2910);
PAINT MONO (-2915 2910);
DISPLAY INVISIBLE (-2915 2910);
FORCEPROP 1 LASTPIN (-2925 2900) BN 0
J 2
(-2873 2908);
DISPLAY 0.617021 (-2873 2908);
PAINT PINK (-2873 2908);
FORCEPROP 2 LAST CDS_LIB mstr_standard
J 0
(-2875 2900);
PAINT MONO (-2875 2900);
DISPLAY INVISIBLE (-2875 2900);
FORCEPROP 1 LAST PATH I124
J 2
(-2873 2900);
DISPLAY 0.872340 (-2873 2900);
PAINT GREEN (-2873 2900);
DISPLAY INVISIBLE (-2873 2900);
FORCEPROP 1 LAST BODY_TYPE PLUMBING
J 2
(-2875 2850);
DISPLAY 1.595745 (-2875 2850);
PAINT GREEN (-2875 2850);
DISPLAY INVISIBLE (-2875 2850);
FORCEPROP 1 LAST HDL_TAP TRUE
J 2
(-3200 2775);
DISPLAY 1.595745 (-3200 2775);
PAINT GREEN (-3200 2775);
DISPLAY INVISIBLE (-3200 2775);
FORCEADD TAP..6
R 2
(-2875 3000);
FORCEPROP 3 LASTPIN (-2925 3000) SIG_NAME M_A_DQS_DN<2>
J 0
(-2915 3010);
DISPLAY 0.659574 (-2915 3010);
PAINT MONO (-2915 3010);
DISPLAY INVISIBLE (-2915 3010);
FORCEPROP 1 LASTPIN (-2925 3000) BN 2
J 2
(-2873 3008);
DISPLAY 0.617021 (-2873 3008);
PAINT PINK (-2873 3008);
FORCEPROP 2 LAST CDS_LIB mstr_standard
J 0
(-2875 3000);
PAINT MONO (-2875 3000);
DISPLAY INVISIBLE (-2875 3000);
FORCEPROP 1 LAST PATH I125
J 2
(-2873 3000);
DISPLAY 0.872340 (-2873 3000);
PAINT GREEN (-2873 3000);
DISPLAY INVISIBLE (-2873 3000);
FORCEPROP 1 LAST BODY_TYPE PLUMBING
J 2
(-2875 2950);
DISPLAY 1.595745 (-2875 2950);
PAINT GREEN (-2875 2950);
DISPLAY INVISIBLE (-2875 2950);
FORCEPROP 1 LAST HDL_TAP TRUE
J 2
(-3200 2875);
DISPLAY 1.595745 (-3200 2875);
PAINT GREEN (-3200 2875);
DISPLAY INVISIBLE (-3200 2875);
FORCEADD TAP..6
R 2
(-2875 2950);
FORCEPROP 3 LASTPIN (-2925 2950) SIG_NAME M_A_DQS_DN<1>
J 0
(-2915 2960);
DISPLAY 0.659574 (-2915 2960);
PAINT MONO (-2915 2960);
DISPLAY INVISIBLE (-2915 2960);
FORCEPROP 1 LASTPIN (-2925 2950) BN 1
J 2
(-2873 2958);
DISPLAY 0.617021 (-2873 2958);
PAINT PINK (-2873 2958);
FORCEPROP 2 LAST CDS_LIB mstr_standard
J 0
(-2875 2950);
PAINT MONO (-2875 2950);
DISPLAY INVISIBLE (-2875 2950);
FORCEPROP 1 LAST PATH I126
J 2
(-2873 2950);
DISPLAY 0.872340 (-2873 2950);
PAINT GREEN (-2873 2950);
DISPLAY INVISIBLE (-2873 2950);
FORCEPROP 1 LAST BODY_TYPE PLUMBING
J 2
(-2875 2900);
DISPLAY 1.595745 (-2875 2900);
PAINT GREEN (-2875 2900);
DISPLAY INVISIBLE (-2875 2900);
FORCEPROP 1 LAST HDL_TAP TRUE
J 2
(-3200 2825);
DISPLAY 1.595745 (-3200 2825);
PAINT GREEN (-3200 2825);
DISPLAY INVISIBLE (-3200 2825);
FORCEADD TAP..6
R 2
(-2875 2800);
FORCEPROP 3 LASTPIN (-2925 2800) SIG_NAME M_A_MA<17>
J 0
(-2915 2810);
DISPLAY 0.659574 (-2915 2810);
PAINT MONO (-2915 2810);
DISPLAY INVISIBLE (-2915 2810);
FORCEPROP 1 LASTPIN (-2925 2800) BN 17
J 2
(-2873 2808);
DISPLAY 0.617021 (-2873 2808);
PAINT PINK (-2873 2808);
FORCEPROP 2 LAST CDS_LIB mstr_standard
J 0
(-2875 2800);
PAINT MONO (-2875 2800);
DISPLAY INVISIBLE (-2875 2800);
FORCEPROP 1 LAST PATH I127
J 2
(-2873 2800);
DISPLAY 0.872340 (-2873 2800);
PAINT GREEN (-2873 2800);
DISPLAY INVISIBLE (-2873 2800);
FORCEPROP 1 LAST BODY_TYPE PLUMBING
J 2
(-2875 2750);
DISPLAY 1.595745 (-2875 2750);
PAINT GREEN (-2875 2750);
DISPLAY INVISIBLE (-2875 2750);
FORCEPROP 1 LAST HDL_TAP TRUE
J 2
(-3200 2675);
DISPLAY 1.595745 (-3200 2675);
PAINT GREEN (-3200 2675);
DISPLAY INVISIBLE (-3200 2675);
FORCEADD TAP..6
R 2
(-2875 3200);
FORCEPROP 3 LASTPIN (-2925 3200) SIG_NAME M_A_DQS_DN<6>
J 0
(-2915 3210);
DISPLAY 0.659574 (-2915 3210);
PAINT MONO (-2915 3210);
DISPLAY INVISIBLE (-2915 3210);
FORCEPROP 1 LASTPIN (-2925 3200) BN 6
J 2
(-2873 3208);
DISPLAY 0.617021 (-2873 3208);
PAINT PINK (-2873 3208);
FORCEPROP 2 LAST CDS_LIB mstr_standard
J 0
(-2875 3200);
PAINT MONO (-2875 3200);
DISPLAY INVISIBLE (-2875 3200);
FORCEPROP 1 LAST PATH I128
J 2
(-2873 3200);
DISPLAY 0.872340 (-2873 3200);
PAINT GREEN (-2873 3200);
DISPLAY INVISIBLE (-2873 3200);
FORCEPROP 1 LAST BODY_TYPE PLUMBING
J 2
(-2875 3150);
DISPLAY 1.595745 (-2875 3150);
PAINT GREEN (-2875 3150);
DISPLAY INVISIBLE (-2875 3150);
FORCEPROP 1 LAST HDL_TAP TRUE
J 2
(-3200 3075);
DISPLAY 1.595745 (-3200 3075);
PAINT GREEN (-3200 3075);
DISPLAY INVISIBLE (-3200 3075);
FORCEADD TAP..6
R 2
(-2875 3250);
FORCEPROP 3 LASTPIN (-2925 3250) SIG_NAME M_A_DQS_DN<7>
J 0
(-2915 3260);
DISPLAY 0.659574 (-2915 3260);
PAINT MONO (-2915 3260);
DISPLAY INVISIBLE (-2915 3260);
FORCEPROP 1 LASTPIN (-2925 3250) BN 7
J 2
(-2873 3258);
DISPLAY 0.617021 (-2873 3258);
PAINT PINK (-2873 3258);
FORCEPROP 2 LAST CDS_LIB mstr_standard
J 0
(-2875 3250);
PAINT MONO (-2875 3250);
DISPLAY INVISIBLE (-2875 3250);
FORCEPROP 1 LAST PATH I129
J 2
(-2873 3250);
DISPLAY 0.872340 (-2873 3250);
PAINT GREEN (-2873 3250);
DISPLAY INVISIBLE (-2873 3250);
FORCEPROP 1 LAST BODY_TYPE PLUMBING
J 2
(-2875 3200);
DISPLAY 1.595745 (-2875 3200);
PAINT GREEN (-2875 3200);
DISPLAY INVISIBLE (-2875 3200);
FORCEPROP 1 LAST HDL_TAP TRUE
J 2
(-3200 3125);
DISPLAY 1.595745 (-3200 3125);
PAINT GREEN (-3200 3125);
DISPLAY INVISIBLE (-3200 3125);
FORCEADD TAP..6
(-5600 1100);
FORCEPROP 3 LASTPIN (-5550 1100) SIG_NAME M_A_ECC<0>
J 0
(-5540 1110);
DISPLAY 0.659574 (-5540 1110);
PAINT MONO (-5540 1110);
DISPLAY INVISIBLE (-5540 1110);
FORCEPROP 1 LASTPIN (-5550 1100) BN 0
J 0
(-5602 1108);
DISPLAY 0.617021 (-5602 1108);
PAINT PINK (-5602 1108);
FORCEPROP 2 LAST CDS_LIB mstr_standard
J 0
(-5600 1100);
PAINT MONO (-5600 1100);
DISPLAY INVISIBLE (-5600 1100);
FORCEPROP 1 LAST PATH I13
J 0
(-5602 1100);
DISPLAY 0.872340 (-5602 1100);
PAINT GREEN (-5602 1100);
DISPLAY INVISIBLE (-5602 1100);
FORCEPROP 1 LAST BODY_TYPE PLUMBING
J 0
(-5600 1050);
DISPLAY 1.595745 (-5600 1050);
PAINT GREEN (-5600 1050);
DISPLAY INVISIBLE (-5600 1050);
FORCEPROP 1 LAST HDL_TAP TRUE
J 0
(-5275 975);
DISPLAY 1.595745 (-5275 975);
PAINT GREEN (-5275 975);
DISPLAY INVISIBLE (-5275 975);
FORCEADD TAP..6
R 2
(-2875 3150);
FORCEPROP 3 LASTPIN (-2925 3150) SIG_NAME M_A_DQS_DN<5>
J 0
(-2915 3160);
DISPLAY 0.659574 (-2915 3160);
PAINT MONO (-2915 3160);
DISPLAY INVISIBLE (-2915 3160);
FORCEPROP 1 LASTPIN (-2925 3150) BN 5
J 2
(-2873 3158);
DISPLAY 0.617021 (-2873 3158);
PAINT PINK (-2873 3158);
FORCEPROP 2 LAST CDS_LIB mstr_standard
J 0
(-2875 3150);
PAINT MONO (-2875 3150);
DISPLAY INVISIBLE (-2875 3150);
FORCEPROP 1 LAST PATH I130
J 2
(-2873 3150);
DISPLAY 0.872340 (-2873 3150);
PAINT GREEN (-2873 3150);
DISPLAY INVISIBLE (-2873 3150);
FORCEPROP 1 LAST BODY_TYPE PLUMBING
J 2
(-2875 3100);
DISPLAY 1.595745 (-2875 3100);
PAINT GREEN (-2875 3100);
DISPLAY INVISIBLE (-2875 3100);
FORCEPROP 1 LAST HDL_TAP TRUE
J 2
(-3200 3025);
DISPLAY 1.595745 (-3200 3025);
PAINT GREEN (-3200 3025);
DISPLAY INVISIBLE (-3200 3025);
FORCEADD TAP..6
R 2
(-2875 3100);
FORCEPROP 3 LASTPIN (-2925 3100) SIG_NAME M_A_DQS_DN<4>
J 0
(-2915 3110);
DISPLAY 0.659574 (-2915 3110);
PAINT MONO (-2915 3110);
DISPLAY INVISIBLE (-2915 3110);
FORCEPROP 1 LASTPIN (-2925 3100) BN 4
J 2
(-2873 3108);
DISPLAY 0.617021 (-2873 3108);
PAINT PINK (-2873 3108);
FORCEPROP 2 LAST CDS_LIB mstr_standard
J 0
(-2875 3100);
PAINT MONO (-2875 3100);
DISPLAY INVISIBLE (-2875 3100);
FORCEPROP 1 LAST PATH I131
J 2
(-2873 3100);
DISPLAY 0.872340 (-2873 3100);
PAINT GREEN (-2873 3100);
DISPLAY INVISIBLE (-2873 3100);
FORCEPROP 1 LAST BODY_TYPE PLUMBING
J 2
(-2875 3050);
DISPLAY 1.595745 (-2875 3050);
PAINT GREEN (-2875 3050);
DISPLAY INVISIBLE (-2875 3050);
FORCEPROP 1 LAST HDL_TAP TRUE
J 2
(-3200 2975);
DISPLAY 1.595745 (-3200 2975);
PAINT GREEN (-3200 2975);
DISPLAY INVISIBLE (-3200 2975);
FORCEADD TAP..6
R 2
(-2875 3050);
FORCEPROP 3 LASTPIN (-2925 3050) SIG_NAME M_A_DQS_DN<3>
J 0
(-2915 3060);
DISPLAY 0.659574 (-2915 3060);
PAINT MONO (-2915 3060);
DISPLAY INVISIBLE (-2915 3060);
FORCEPROP 1 LASTPIN (-2925 3050) BN 3
J 2
(-2873 3058);
DISPLAY 0.617021 (-2873 3058);
PAINT PINK (-2873 3058);
FORCEPROP 2 LAST CDS_LIB mstr_standard
J 0
(-2875 3050);
PAINT MONO (-2875 3050);
DISPLAY INVISIBLE (-2875 3050);
FORCEPROP 1 LAST PATH I132
J 2
(-2873 3050);
DISPLAY 0.872340 (-2873 3050);
PAINT GREEN (-2873 3050);
DISPLAY INVISIBLE (-2873 3050);
FORCEPROP 1 LAST BODY_TYPE PLUMBING
J 2
(-2875 3000);
DISPLAY 1.595745 (-2875 3000);
PAINT GREEN (-2875 3000);
DISPLAY INVISIBLE (-2875 3000);
FORCEPROP 1 LAST HDL_TAP TRUE
J 2
(-3200 2925);
DISPLAY 1.595745 (-3200 2925);
PAINT GREEN (-3200 2925);
DISPLAY INVISIBLE (-3200 2925);
FORCEADD TAP..6
R 2
(-2875 3500);
FORCEPROP 3 LASTPIN (-2925 3500) SIG_NAME M_A_DQS_DN<12>
J 0
(-2915 3510);
DISPLAY 0.659574 (-2915 3510);
PAINT MONO (-2915 3510);
DISPLAY INVISIBLE (-2915 3510);
FORCEPROP 1 LASTPIN (-2925 3500) BN 12
J 2
(-2873 3508);
DISPLAY 0.617021 (-2873 3508);
PAINT PINK (-2873 3508);
FORCEPROP 2 LAST CDS_LIB mstr_standard
J 0
(-2875 3500);
PAINT MONO (-2875 3500);
DISPLAY INVISIBLE (-2875 3500);
FORCEPROP 1 LAST PATH I133
J 2
(-2873 3500);
DISPLAY 0.872340 (-2873 3500);
PAINT GREEN (-2873 3500);
DISPLAY INVISIBLE (-2873 3500);
FORCEPROP 1 LAST BODY_TYPE PLUMBING
J 2
(-2875 3450);
DISPLAY 1.595745 (-2875 3450);
PAINT GREEN (-2875 3450);
DISPLAY INVISIBLE (-2875 3450);
FORCEPROP 1 LAST HDL_TAP TRUE
J 2
(-3200 3375);
DISPLAY 1.595745 (-3200 3375);
PAINT GREEN (-3200 3375);
DISPLAY INVISIBLE (-3200 3375);
FORCEADD TAP..6
R 2
(-2875 3450);
FORCEPROP 3 LASTPIN (-2925 3450) SIG_NAME M_A_DQS_DN<11>
J 0
(-2915 3460);
DISPLAY 0.659574 (-2915 3460);
PAINT MONO (-2915 3460);
DISPLAY INVISIBLE (-2915 3460);
FORCEPROP 1 LASTPIN (-2925 3450) BN 11
J 2
(-2873 3458);
DISPLAY 0.617021 (-2873 3458);
PAINT PINK (-2873 3458);
FORCEPROP 2 LAST CDS_LIB mstr_standard
J 0
(-2875 3450);
PAINT MONO (-2875 3450);
DISPLAY INVISIBLE (-2875 3450);
FORCEPROP 1 LAST PATH I134
J 2
(-2873 3450);
DISPLAY 0.872340 (-2873 3450);
PAINT GREEN (-2873 3450);
DISPLAY INVISIBLE (-2873 3450);
FORCEPROP 1 LAST BODY_TYPE PLUMBING
J 2
(-2875 3400);
DISPLAY 1.595745 (-2875 3400);
PAINT GREEN (-2875 3400);
DISPLAY INVISIBLE (-2875 3400);
FORCEPROP 1 LAST HDL_TAP TRUE
J 2
(-3200 3325);
DISPLAY 1.595745 (-3200 3325);
PAINT GREEN (-3200 3325);
DISPLAY INVISIBLE (-3200 3325);
FORCEADD TAP..6
R 2
(-2875 3400);
FORCEPROP 3 LASTPIN (-2925 3400) SIG_NAME M_A_DQS_DN<10>
J 0
(-2915 3410);
DISPLAY 0.659574 (-2915 3410);
PAINT MONO (-2915 3410);
DISPLAY INVISIBLE (-2915 3410);
FORCEPROP 1 LASTPIN (-2925 3400) BN 10
J 2
(-2873 3408);
DISPLAY 0.617021 (-2873 3408);
PAINT PINK (-2873 3408);
FORCEPROP 2 LAST CDS_LIB mstr_standard
J 0
(-2875 3400);
PAINT MONO (-2875 3400);
DISPLAY INVISIBLE (-2875 3400);
FORCEPROP 1 LAST PATH I135
J 2
(-2873 3400);
DISPLAY 0.872340 (-2873 3400);
PAINT GREEN (-2873 3400);
DISPLAY INVISIBLE (-2873 3400);
FORCEPROP 1 LAST BODY_TYPE PLUMBING
J 2
(-2875 3350);
DISPLAY 1.595745 (-2875 3350);
PAINT GREEN (-2875 3350);
DISPLAY INVISIBLE (-2875 3350);
FORCEPROP 1 LAST HDL_TAP TRUE
J 2
(-3200 3275);
DISPLAY 1.595745 (-3200 3275);
PAINT GREEN (-3200 3275);
DISPLAY INVISIBLE (-3200 3275);
FORCEADD TAP..6
R 2
(-2875 3350);
FORCEPROP 3 LASTPIN (-2925 3350) SIG_NAME M_A_DQS_DN<9>
J 0
(-2915 3360);
DISPLAY 0.659574 (-2915 3360);
PAINT MONO (-2915 3360);
DISPLAY INVISIBLE (-2915 3360);
FORCEPROP 1 LASTPIN (-2925 3350) BN 9
J 2
(-2873 3358);
DISPLAY 0.617021 (-2873 3358);
PAINT PINK (-2873 3358);
FORCEPROP 2 LAST CDS_LIB mstr_standard
J 0
(-2875 3350);
PAINT MONO (-2875 3350);
DISPLAY INVISIBLE (-2875 3350);
FORCEPROP 1 LAST PATH I136
J 2
(-2873 3350);
DISPLAY 0.872340 (-2873 3350);
PAINT GREEN (-2873 3350);
DISPLAY INVISIBLE (-2873 3350);
FORCEPROP 1 LAST BODY_TYPE PLUMBING
J 2
(-2875 3300);
DISPLAY 1.595745 (-2875 3300);
PAINT GREEN (-2875 3300);
DISPLAY INVISIBLE (-2875 3300);
FORCEPROP 1 LAST HDL_TAP TRUE
J 2
(-3200 3225);
DISPLAY 1.595745 (-3200 3225);
PAINT GREEN (-3200 3225);
DISPLAY INVISIBLE (-3200 3225);
FORCEADD TAP..6
R 2
(-2875 3300);
FORCEPROP 3 LASTPIN (-2925 3300) SIG_NAME M_A_DQS_DN<8>
J 0
(-2915 3310);
DISPLAY 0.659574 (-2915 3310);
PAINT MONO (-2915 3310);
DISPLAY INVISIBLE (-2915 3310);
FORCEPROP 1 LASTPIN (-2925 3300) BN 8
J 2
(-2873 3308);
DISPLAY 0.617021 (-2873 3308);
PAINT PINK (-2873 3308);
FORCEPROP 2 LAST CDS_LIB mstr_standard
J 0
(-2875 3300);
PAINT MONO (-2875 3300);
DISPLAY INVISIBLE (-2875 3300);
FORCEPROP 1 LAST PATH I137
J 2
(-2873 3300);
DISPLAY 0.872340 (-2873 3300);
PAINT GREEN (-2873 3300);
DISPLAY INVISIBLE (-2873 3300);
FORCEPROP 1 LAST BODY_TYPE PLUMBING
J 2
(-2875 3250);
DISPLAY 1.595745 (-2875 3250);
PAINT GREEN (-2875 3250);
DISPLAY INVISIBLE (-2875 3250);
FORCEPROP 1 LAST HDL_TAP TRUE
J 2
(-3200 3175);
DISPLAY 1.595745 (-3200 3175);
PAINT GREEN (-3200 3175);
DISPLAY INVISIBLE (-3200 3175);
FORCEADD TAP..6
R 2
(-2875 3700);
FORCEPROP 3 LASTPIN (-2925 3700) SIG_NAME M_A_DQS_DN<16>
J 0
(-2915 3710);
DISPLAY 0.659574 (-2915 3710);
PAINT MONO (-2915 3710);
DISPLAY INVISIBLE (-2915 3710);
FORCEPROP 1 LASTPIN (-2925 3700) BN 16
J 2
(-2873 3708);
DISPLAY 0.617021 (-2873 3708);
PAINT PINK (-2873 3708);
FORCEPROP 2 LAST CDS_LIB mstr_standard
J 0
(-2875 3700);
PAINT MONO (-2875 3700);
DISPLAY INVISIBLE (-2875 3700);
FORCEPROP 1 LAST PATH I138
J 2
(-2873 3700);
DISPLAY 0.872340 (-2873 3700);
PAINT GREEN (-2873 3700);
DISPLAY INVISIBLE (-2873 3700);
FORCEPROP 1 LAST BODY_TYPE PLUMBING
J 2
(-2875 3650);
DISPLAY 1.595745 (-2875 3650);
PAINT GREEN (-2875 3650);
DISPLAY INVISIBLE (-2875 3650);
FORCEPROP 1 LAST HDL_TAP TRUE
J 2
(-3200 3575);
DISPLAY 1.595745 (-3200 3575);
PAINT GREEN (-3200 3575);
DISPLAY INVISIBLE (-3200 3575);
FORCEADD TAP..6
R 2
(-2875 3750);
FORCEPROP 3 LASTPIN (-2925 3750) SIG_NAME M_A_DQS_DN<17>
J 0
(-2915 3760);
DISPLAY 0.659574 (-2915 3760);
PAINT MONO (-2915 3760);
DISPLAY INVISIBLE (-2915 3760);
FORCEPROP 1 LASTPIN (-2925 3750) BN 17
J 2
(-2873 3758);
DISPLAY 0.617021 (-2873 3758);
PAINT PINK (-2873 3758);
FORCEPROP 2 LAST CDS_LIB mstr_standard
J 0
(-2875 3750);
PAINT MONO (-2875 3750);
DISPLAY INVISIBLE (-2875 3750);
FORCEPROP 1 LAST PATH I139
J 2
(-2873 3750);
DISPLAY 0.872340 (-2873 3750);
PAINT GREEN (-2873 3750);
DISPLAY INVISIBLE (-2873 3750);
FORCEPROP 1 LAST BODY_TYPE PLUMBING
J 2
(-2875 3700);
DISPLAY 1.595745 (-2875 3700);
PAINT GREEN (-2875 3700);
DISPLAY INVISIBLE (-2875 3700);
FORCEPROP 1 LAST HDL_TAP TRUE
J 2
(-3200 3625);
DISPLAY 1.595745 (-3200 3625);
PAINT GREEN (-3200 3625);
DISPLAY INVISIBLE (-3200 3625);
FORCEADD TAP..6
(-5600 1150);
FORCEPROP 3 LASTPIN (-5550 1150) SIG_NAME M_A_ECC<1>
J 0
(-5540 1160);
DISPLAY 0.659574 (-5540 1160);
PAINT MONO (-5540 1160);
DISPLAY INVISIBLE (-5540 1160);
FORCEPROP 1 LASTPIN (-5550 1150) BN 1
J 0
(-5602 1158);
DISPLAY 0.617021 (-5602 1158);
PAINT PINK (-5602 1158);
FORCEPROP 2 LAST CDS_LIB mstr_standard
J 0
(-5600 1150);
PAINT MONO (-5600 1150);
DISPLAY INVISIBLE (-5600 1150);
FORCEPROP 1 LAST PATH I14
J 0
(-5602 1150);
DISPLAY 0.872340 (-5602 1150);
PAINT GREEN (-5602 1150);
DISPLAY INVISIBLE (-5602 1150);
FORCEPROP 1 LAST BODY_TYPE PLUMBING
J 0
(-5600 1100);
DISPLAY 1.595745 (-5600 1100);
PAINT GREEN (-5600 1100);
DISPLAY INVISIBLE (-5600 1100);
FORCEPROP 1 LAST HDL_TAP TRUE
J 0
(-5275 1025);
DISPLAY 1.595745 (-5275 1025);
PAINT GREEN (-5275 1025);
DISPLAY INVISIBLE (-5275 1025);
FORCEADD TAP..6
R 2
(-2875 3650);
FORCEPROP 3 LASTPIN (-2925 3650) SIG_NAME M_A_DQS_DN<15>
J 0
(-2915 3660);
DISPLAY 0.659574 (-2915 3660);
PAINT MONO (-2915 3660);
DISPLAY INVISIBLE (-2915 3660);
FORCEPROP 1 LASTPIN (-2925 3650) BN 15
J 2
(-2873 3658);
DISPLAY 0.617021 (-2873 3658);
PAINT PINK (-2873 3658);
FORCEPROP 2 LAST CDS_LIB mstr_standard
J 0
(-2875 3650);
PAINT MONO (-2875 3650);
DISPLAY INVISIBLE (-2875 3650);
FORCEPROP 1 LAST PATH I140
J 2
(-2873 3650);
DISPLAY 0.872340 (-2873 3650);
PAINT GREEN (-2873 3650);
DISPLAY INVISIBLE (-2873 3650);
FORCEPROP 1 LAST BODY_TYPE PLUMBING
J 2
(-2875 3600);
DISPLAY 1.595745 (-2875 3600);
PAINT GREEN (-2875 3600);
DISPLAY INVISIBLE (-2875 3600);
FORCEPROP 1 LAST HDL_TAP TRUE
J 2
(-3200 3525);
DISPLAY 1.595745 (-3200 3525);
PAINT GREEN (-3200 3525);
DISPLAY INVISIBLE (-3200 3525);
FORCEADD TAP..6
R 2
(-2875 3600);
FORCEPROP 3 LASTPIN (-2925 3600) SIG_NAME M_A_DQS_DN<14>
J 0
(-2915 3610);
DISPLAY 0.659574 (-2915 3610);
PAINT MONO (-2915 3610);
DISPLAY INVISIBLE (-2915 3610);
FORCEPROP 1 LASTPIN (-2925 3600) BN 14
J 2
(-2873 3608);
DISPLAY 0.617021 (-2873 3608);
PAINT PINK (-2873 3608);
FORCEPROP 2 LAST CDS_LIB mstr_standard
J 0
(-2875 3600);
PAINT MONO (-2875 3600);
DISPLAY INVISIBLE (-2875 3600);
FORCEPROP 1 LAST PATH I141
J 2
(-2873 3600);
DISPLAY 0.872340 (-2873 3600);
PAINT GREEN (-2873 3600);
DISPLAY INVISIBLE (-2873 3600);
FORCEPROP 1 LAST BODY_TYPE PLUMBING
J 2
(-2875 3550);
DISPLAY 1.595745 (-2875 3550);
PAINT GREEN (-2875 3550);
DISPLAY INVISIBLE (-2875 3550);
FORCEPROP 1 LAST HDL_TAP TRUE
J 2
(-3200 3475);
DISPLAY 1.595745 (-3200 3475);
PAINT GREEN (-3200 3475);
DISPLAY INVISIBLE (-3200 3475);
FORCEADD TAP..6
R 2
(-2875 3550);
FORCEPROP 3 LASTPIN (-2925 3550) SIG_NAME M_A_DQS_DN<13>
J 0
(-2915 3560);
DISPLAY 0.659574 (-2915 3560);
PAINT MONO (-2915 3560);
DISPLAY INVISIBLE (-2915 3560);
FORCEPROP 1 LASTPIN (-2925 3550) BN 13
J 2
(-2873 3558);
DISPLAY 0.617021 (-2873 3558);
PAINT PINK (-2873 3558);
FORCEPROP 2 LAST CDS_LIB mstr_standard
J 0
(-2875 3550);
PAINT MONO (-2875 3550);
DISPLAY INVISIBLE (-2875 3550);
FORCEPROP 1 LAST PATH I142
J 2
(-2873 3550);
DISPLAY 0.872340 (-2873 3550);
PAINT GREEN (-2873 3550);
DISPLAY INVISIBLE (-2873 3550);
FORCEPROP 1 LAST BODY_TYPE PLUMBING
J 2
(-2875 3500);
DISPLAY 1.595745 (-2875 3500);
PAINT GREEN (-2875 3500);
DISPLAY INVISIBLE (-2875 3500);
FORCEPROP 1 LAST HDL_TAP TRUE
J 2
(-3200 3425);
DISPLAY 1.595745 (-3200 3425);
PAINT GREEN (-3200 3425);
DISPLAY INVISIBLE (-3200 3425);
FORCEADD TAP..6
R 2
(-2875 3950);
FORCEPROP 3 LASTPIN (-2925 3950) SIG_NAME M_A_DQS_DP<2>
J 0
(-2915 3960);
DISPLAY 0.659574 (-2915 3960);
PAINT MONO (-2915 3960);
DISPLAY INVISIBLE (-2915 3960);
FORCEPROP 1 LASTPIN (-2925 3950) BN 2
J 2
(-2873 3958);
DISPLAY 0.617021 (-2873 3958);
PAINT PINK (-2873 3958);
FORCEPROP 2 LAST CDS_LIB mstr_standard
J 0
(-2875 3950);
PAINT MONO (-2875 3950);
DISPLAY INVISIBLE (-2875 3950);
FORCEPROP 1 LAST PATH I143
J 2
(-2873 3950);
DISPLAY 0.872340 (-2873 3950);
PAINT GREEN (-2873 3950);
DISPLAY INVISIBLE (-2873 3950);
FORCEPROP 1 LAST BODY_TYPE PLUMBING
J 2
(-2875 3900);
DISPLAY 1.595745 (-2875 3900);
PAINT GREEN (-2875 3900);
DISPLAY INVISIBLE (-2875 3900);
FORCEPROP 1 LAST HDL_TAP TRUE
J 2
(-3200 3825);
DISPLAY 1.595745 (-3200 3825);
PAINT GREEN (-3200 3825);
DISPLAY INVISIBLE (-3200 3825);
FORCEADD TAP..6
R 2
(-2875 4000);
FORCEPROP 3 LASTPIN (-2925 4000) SIG_NAME M_A_DQS_DP<3>
J 0
(-2915 4010);
DISPLAY 0.659574 (-2915 4010);
PAINT MONO (-2915 4010);
DISPLAY INVISIBLE (-2915 4010);
FORCEPROP 1 LASTPIN (-2925 4000) BN 3
J 2
(-2873 4008);
DISPLAY 0.617021 (-2873 4008);
PAINT PINK (-2873 4008);
FORCEPROP 2 LAST CDS_LIB mstr_standard
J 0
(-2875 4000);
PAINT MONO (-2875 4000);
DISPLAY INVISIBLE (-2875 4000);
FORCEPROP 1 LAST PATH I144
J 2
(-2873 4000);
DISPLAY 0.872340 (-2873 4000);
PAINT GREEN (-2873 4000);
DISPLAY INVISIBLE (-2873 4000);
FORCEPROP 1 LAST BODY_TYPE PLUMBING
J 2
(-2875 3950);
DISPLAY 1.595745 (-2875 3950);
PAINT GREEN (-2875 3950);
DISPLAY INVISIBLE (-2875 3950);
FORCEPROP 1 LAST HDL_TAP TRUE
J 2
(-3200 3875);
DISPLAY 1.595745 (-3200 3875);
PAINT GREEN (-3200 3875);
DISPLAY INVISIBLE (-3200 3875);
FORCEADD TAP..6
R 2
(-2875 3900);
FORCEPROP 3 LASTPIN (-2925 3900) SIG_NAME M_A_DQS_DP<1>
J 0
(-2915 3910);
DISPLAY 0.659574 (-2915 3910);
PAINT MONO (-2915 3910);
DISPLAY INVISIBLE (-2915 3910);
FORCEPROP 1 LASTPIN (-2925 3900) BN 1
J 2
(-2873 3908);
DISPLAY 0.617021 (-2873 3908);
PAINT PINK (-2873 3908);
FORCEPROP 2 LAST CDS_LIB mstr_standard
J 0
(-2875 3900);
PAINT MONO (-2875 3900);
DISPLAY INVISIBLE (-2875 3900);
FORCEPROP 1 LAST PATH I145
J 2
(-2873 3900);
DISPLAY 0.872340 (-2873 3900);
PAINT GREEN (-2873 3900);
DISPLAY INVISIBLE (-2873 3900);
FORCEPROP 1 LAST BODY_TYPE PLUMBING
J 2
(-2875 3850);
DISPLAY 1.595745 (-2875 3850);
PAINT GREEN (-2875 3850);
DISPLAY INVISIBLE (-2875 3850);
FORCEPROP 1 LAST HDL_TAP TRUE
J 2
(-3200 3775);
DISPLAY 1.595745 (-3200 3775);
PAINT GREEN (-3200 3775);
DISPLAY INVISIBLE (-3200 3775);
FORCEADD TAP..6
R 2
(-2875 3850);
FORCEPROP 3 LASTPIN (-2925 3850) SIG_NAME M_A_DQS_DP<0>
J 0
(-2915 3860);
DISPLAY 0.659574 (-2915 3860);
PAINT MONO (-2915 3860);
DISPLAY INVISIBLE (-2915 3860);
FORCEPROP 1 LASTPIN (-2925 3850) BN 0
J 2
(-2873 3858);
DISPLAY 0.617021 (-2873 3858);
PAINT PINK (-2873 3858);
FORCEPROP 2 LAST CDS_LIB mstr_standard
J 0
(-2875 3850);
PAINT MONO (-2875 3850);
DISPLAY INVISIBLE (-2875 3850);
FORCEPROP 1 LAST PATH I146
J 2
(-2873 3850);
DISPLAY 0.872340 (-2873 3850);
PAINT GREEN (-2873 3850);
DISPLAY INVISIBLE (-2873 3850);
FORCEPROP 1 LAST BODY_TYPE PLUMBING
J 2
(-2875 3800);
DISPLAY 1.595745 (-2875 3800);
PAINT GREEN (-2875 3800);
DISPLAY INVISIBLE (-2875 3800);
FORCEPROP 1 LAST HDL_TAP TRUE
J 2
(-3200 3725);
DISPLAY 1.595745 (-3200 3725);
PAINT GREEN (-3200 3725);
DISPLAY INVISIBLE (-3200 3725);
FORCEADD OFFPAGE..2
(-2025 550);
FORCEPROP 2 LAST $XR1 44 
J 0
(-1746 550);
DISPLAY 0.638298 (-1746 550);
PAINT MONO (-1746 550);
FORCEPROP 2 LAST $XR0 43 
J 0
(-1836 550);
DISPLAY 0.638298 (-1836 550);
PAINT MONO (-1836 550);
FORCEPROP 2 LAST CDS_LIB mstr_standard
J 0
(-2025 550);
PAINT MONO (-2025 550);
DISPLAY INVISIBLE (-2025 550);
FORCEPROP 2 LAST PATH I147
J 0
(-1850 625);
DISPLAY 1.021277 (-1850 625);
PAINT ORANGE (-1850 625);
DISPLAY INVISIBLE (-1850 625);
FORCEPROP 1 LAST OFFPAGE TRUE
J 0
(-1700 425);
DISPLAY 1.170213 (-1700 425);
PAINT GREEN (-1700 425);
DISPLAY INVISIBLE (-1700 425);
FORCEPROP 1 LAST COMMENT_BODY TRUE
J 0
(-2070 455);
DISPLAY 1.170213 (-2070 455);
PAINT GREEN (-2070 455);
DISPLAY INVISIBLE (-2070 455);
FORCEADD OFFPAGE..4
(-2025 600);
FORCEPROP 2 LAST $XR1 44 
J 0
(-1749 600);
DISPLAY 0.638298 (-1749 600);
PAINT MONO (-1749 600);
FORCEPROP 2 LAST $XR0 43 
J 0
(-1839 600);
DISPLAY 0.638298 (-1839 600);
PAINT MONO (-1839 600);
FORCEPROP 2 LAST CDS_LIB mstr_standard
J 0
(-2025 600);
PAINT MONO (-2025 600);
DISPLAY INVISIBLE (-2025 600);
FORCEPROP 2 LAST PATH I148
J 0
(-1850 675);
DISPLAY 1.021277 (-1850 675);
PAINT ORANGE (-1850 675);
DISPLAY INVISIBLE (-1850 675);
FORCEPROP 1 LAST OFFPAGE TRUE
J 0
(-1700 475);
DISPLAY 1.170213 (-1700 475);
PAINT GREEN (-1700 475);
DISPLAY INVISIBLE (-1700 475);
FORCEPROP 1 LAST COMMENT_BODY TRUE
J 0
(-2050 500);
DISPLAY 1.170213 (-2050 500);
PAINT GREEN (-2050 500);
DISPLAY INVISIBLE (-2050 500);
FORCEADD OFFPAGE..2
(-2025 650);
FORCEPROP 2 LAST $XR1 44 
J 0
(-1746 650);
DISPLAY 0.638298 (-1746 650);
PAINT MONO (-1746 650);
FORCEPROP 2 LAST $XR0 43 
J 0
(-1836 650);
DISPLAY 0.638298 (-1836 650);
PAINT MONO (-1836 650);
FORCEPROP 2 LAST CDS_LIB mstr_standard
J 0
(-2025 650);
PAINT MONO (-2025 650);
DISPLAY INVISIBLE (-2025 650);
FORCEPROP 2 LAST PATH I149
J 0
(-1850 725);
DISPLAY 1.021277 (-1850 725);
PAINT ORANGE (-1850 725);
DISPLAY INVISIBLE (-1850 725);
FORCEPROP 1 LAST OFFPAGE TRUE
J 0
(-1700 525);
DISPLAY 1.170213 (-1700 525);
PAINT GREEN (-1700 525);
DISPLAY INVISIBLE (-1700 525);
FORCEPROP 1 LAST COMMENT_BODY TRUE
J 0
(-2070 555);
DISPLAY 1.170213 (-2070 555);
PAINT GREEN (-2070 555);
DISPLAY INVISIBLE (-2070 555);
FORCEADD TAP..6
(-5600 1200);
FORCEPROP 3 LASTPIN (-5550 1200) SIG_NAME M_A_ECC<2>
J 0
(-5540 1210);
DISPLAY 0.659574 (-5540 1210);
PAINT MONO (-5540 1210);
DISPLAY INVISIBLE (-5540 1210);
FORCEPROP 1 LASTPIN (-5550 1200) BN 2
J 0
(-5602 1208);
DISPLAY 0.617021 (-5602 1208);
PAINT PINK (-5602 1208);
FORCEPROP 2 LAST CDS_LIB mstr_standard
J 0
(-5600 1200);
PAINT MONO (-5600 1200);
DISPLAY INVISIBLE (-5600 1200);
FORCEPROP 1 LAST PATH I15
J 0
(-5602 1200);
DISPLAY 0.872340 (-5602 1200);
PAINT GREEN (-5602 1200);
DISPLAY INVISIBLE (-5602 1200);
FORCEPROP 1 LAST BODY_TYPE PLUMBING
J 0
(-5600 1150);
DISPLAY 1.595745 (-5600 1150);
PAINT GREEN (-5600 1150);
DISPLAY INVISIBLE (-5600 1150);
FORCEPROP 1 LAST HDL_TAP TRUE
J 0
(-5275 1075);
DISPLAY 1.595745 (-5275 1075);
PAINT GREEN (-5275 1075);
DISPLAY INVISIBLE (-5275 1075);
FORCEADD OFFPAGE..2
(-2025 950);
FORCEPROP 2 LAST $XR1 44 
J 0
(-1746 950);
DISPLAY 0.638298 (-1746 950);
PAINT MONO (-1746 950);
FORCEPROP 2 LAST $XR0 43 
J 0
(-1836 950);
DISPLAY 0.638298 (-1836 950);
PAINT MONO (-1836 950);
FORCEPROP 2 LAST CDS_LIB mstr_standard
J 0
(-2025 950);
PAINT MONO (-2025 950);
DISPLAY INVISIBLE (-2025 950);
FORCEPROP 2 LAST PATH I150
J 0
(-1850 1025);
DISPLAY 1.021277 (-1850 1025);
PAINT ORANGE (-1850 1025);
DISPLAY INVISIBLE (-1850 1025);
FORCEPROP 1 LAST OFFPAGE TRUE
J 0
(-1700 825);
DISPLAY 1.170213 (-1700 825);
PAINT GREEN (-1700 825);
DISPLAY INVISIBLE (-1700 825);
FORCEPROP 1 LAST COMMENT_BODY TRUE
J 0
(-2070 855);
DISPLAY 1.170213 (-2070 855);
PAINT GREEN (-2070 855);
DISPLAY INVISIBLE (-2070 855);
FORCEADD OFFPAGE..2
(-2025 850);
FORCEPROP 2 LAST $XR1 44 
J 0
(-1746 850);
DISPLAY 0.638298 (-1746 850);
PAINT MONO (-1746 850);
FORCEPROP 2 LAST $XR0 43 
J 0
(-1836 850);
DISPLAY 0.638298 (-1836 850);
PAINT MONO (-1836 850);
FORCEPROP 2 LAST CDS_LIB mstr_standard
J 0
(-2025 850);
PAINT MONO (-2025 850);
DISPLAY INVISIBLE (-2025 850);
FORCEPROP 2 LAST PATH I151
J 0
(-1850 925);
DISPLAY 1.021277 (-1850 925);
PAINT ORANGE (-1850 925);
DISPLAY INVISIBLE (-1850 925);
FORCEPROP 1 LAST OFFPAGE TRUE
J 0
(-1700 725);
DISPLAY 1.170213 (-1700 725);
PAINT GREEN (-1700 725);
DISPLAY INVISIBLE (-1700 725);
FORCEPROP 1 LAST COMMENT_BODY TRUE
J 0
(-2070 755);
DISPLAY 1.170213 (-2070 755);
PAINT GREEN (-2070 755);
DISPLAY INVISIBLE (-2070 755);
FORCEADD OFFPAGE..2
(-2025 1400);
FORCEPROP 2 LAST $XR1 44 
J 0
(-1746 1400);
DISPLAY 0.638298 (-1746 1400);
PAINT MONO (-1746 1400);
FORCEPROP 2 LAST $XR0 43 
J 0
(-1836 1400);
DISPLAY 0.638298 (-1836 1400);
PAINT MONO (-1836 1400);
FORCEPROP 2 LAST CDS_LIB mstr_standard
J 0
(-2025 1400);
PAINT MONO (-2025 1400);
DISPLAY INVISIBLE (-2025 1400);
FORCEPROP 2 LAST PATH I152
J 0
(-1850 1475);
DISPLAY 1.021277 (-1850 1475);
PAINT ORANGE (-1850 1475);
DISPLAY INVISIBLE (-1850 1475);
FORCEPROP 1 LAST OFFPAGE TRUE
J 0
(-1700 1275);
DISPLAY 1.170213 (-1700 1275);
PAINT GREEN (-1700 1275);
DISPLAY INVISIBLE (-1700 1275);
FORCEPROP 1 LAST COMMENT_BODY TRUE
J 0
(-2070 1305);
DISPLAY 1.170213 (-2070 1305);
PAINT GREEN (-2070 1305);
DISPLAY INVISIBLE (-2070 1305);
FORCEADD OFFPAGE..2
(-2025 1650);
FORCEPROP 2 LAST $XR1 44 
J 0
(-1746 1650);
DISPLAY 0.638298 (-1746 1650);
PAINT MONO (-1746 1650);
FORCEPROP 2 LAST $XR0 43 
J 0
(-1836 1650);
DISPLAY 0.638298 (-1836 1650);
PAINT MONO (-1836 1650);
FORCEPROP 2 LAST CDS_LIB mstr_standard
J 0
(-2025 1650);
PAINT MONO (-2025 1650);
DISPLAY INVISIBLE (-2025 1650);
FORCEPROP 2 LAST PATH I153
J 0
(-1850 1725);
DISPLAY 1.021277 (-1850 1725);
PAINT ORANGE (-1850 1725);
DISPLAY INVISIBLE (-1850 1725);
FORCEPROP 1 LAST OFFPAGE TRUE
J 0
(-1700 1525);
DISPLAY 1.170213 (-1700 1525);
PAINT GREEN (-1700 1525);
DISPLAY INVISIBLE (-1700 1525);
FORCEPROP 1 LAST COMMENT_BODY TRUE
J 0
(-2070 1555);
DISPLAY 1.170213 (-2070 1555);
PAINT GREEN (-2070 1555);
DISPLAY INVISIBLE (-2070 1555);
FORCEADD OFFPAGE..2
(-2025 1900);
FORCEPROP 2 LAST $XR1 44 
J 0
(-1746 1900);
DISPLAY 0.638298 (-1746 1900);
PAINT MONO (-1746 1900);
FORCEPROP 2 LAST $XR0 43 
J 0
(-1836 1900);
DISPLAY 0.638298 (-1836 1900);
PAINT MONO (-1836 1900);
FORCEPROP 2 LAST CDS_LIB mstr_standard
J 0
(-2025 1900);
PAINT MONO (-2025 1900);
DISPLAY INVISIBLE (-2025 1900);
FORCEPROP 2 LAST PATH I154
J 0
(-1850 1975);
DISPLAY 1.021277 (-1850 1975);
PAINT ORANGE (-1850 1975);
DISPLAY INVISIBLE (-1850 1975);
FORCEPROP 1 LAST OFFPAGE TRUE
J 0
(-1700 1775);
DISPLAY 1.170213 (-1700 1775);
PAINT GREEN (-1700 1775);
DISPLAY INVISIBLE (-1700 1775);
FORCEPROP 1 LAST COMMENT_BODY TRUE
J 0
(-2070 1805);
DISPLAY 1.170213 (-2070 1805);
PAINT GREEN (-2070 1805);
DISPLAY INVISIBLE (-2070 1805);
FORCEADD OFFPAGE..2
(-2025 2850);
FORCEPROP 2 LAST $XR1 44 
J 0
(-1746 2850);
DISPLAY 0.638298 (-1746 2850);
PAINT MONO (-1746 2850);
FORCEPROP 2 LAST $XR0 43 
J 0
(-1836 2850);
DISPLAY 0.638298 (-1836 2850);
PAINT MONO (-1836 2850);
FORCEPROP 2 LAST CDS_LIB mstr_standard
J 0
(-2025 2850);
PAINT MONO (-2025 2850);
DISPLAY INVISIBLE (-2025 2850);
FORCEPROP 2 LAST PATH I155
J 0
(-1850 2925);
DISPLAY 1.021277 (-1850 2925);
PAINT ORANGE (-1850 2925);
DISPLAY INVISIBLE (-1850 2925);
FORCEPROP 1 LAST OFFPAGE TRUE
J 0
(-1700 2725);
DISPLAY 1.170213 (-1700 2725);
PAINT GREEN (-1700 2725);
DISPLAY INVISIBLE (-1700 2725);
FORCEPROP 1 LAST COMMENT_BODY TRUE
J 0
(-2070 2755);
DISPLAY 1.170213 (-2070 2755);
PAINT GREEN (-2070 2755);
DISPLAY INVISIBLE (-2070 2755);
FORCEADD OFFPAGE..3
(-2025 3800);
FORCEPROP 2 LAST $XR1 44 
J 0
(-1721 3800);
DISPLAY 0.638298 (-1721 3800);
PAINT MONO (-1721 3800);
FORCEPROP 2 LAST $XR0 43 
J 0
(-1811 3800);
DISPLAY 0.638298 (-1811 3800);
PAINT MONO (-1811 3800);
FORCEPROP 2 LAST CDS_LIB mstr_standard
J 0
(-2025 3800);
PAINT MONO (-2025 3800);
DISPLAY INVISIBLE (-2025 3800);
FORCEPROP 2 LAST PATH I156
J 0
(-1825 3875);
DISPLAY 1.021277 (-1825 3875);
PAINT ORANGE (-1825 3875);
DISPLAY INVISIBLE (-1825 3875);
FORCEPROP 1 LAST OFFPAGE TRUE
J 0
(-1700 3675);
DISPLAY 1.170213 (-1700 3675);
PAINT GREEN (-1700 3675);
DISPLAY INVISIBLE (-1700 3675);
FORCEPROP 1 LAST COMMENT_BODY TRUE
J 0
(-2075 3700);
DISPLAY 1.170213 (-2075 3700);
PAINT GREEN (-2075 3700);
DISPLAY INVISIBLE (-2075 3700);
FORCEADD TAP..6
R 2
(-2875 4050);
FORCEPROP 3 LASTPIN (-2925 4050) SIG_NAME M_A_DQS_DP<4>
J 0
(-2915 4060);
DISPLAY 0.659574 (-2915 4060);
PAINT MONO (-2915 4060);
DISPLAY INVISIBLE (-2915 4060);
FORCEPROP 1 LASTPIN (-2925 4050) BN 4
J 2
(-2873 4058);
DISPLAY 0.617021 (-2873 4058);
PAINT PINK (-2873 4058);
FORCEPROP 2 LAST CDS_LIB mstr_standard
J 0
(-2875 4050);
PAINT MONO (-2875 4050);
DISPLAY INVISIBLE (-2875 4050);
FORCEPROP 1 LAST PATH I157
J 2
(-2873 4050);
DISPLAY 0.872340 (-2873 4050);
PAINT GREEN (-2873 4050);
DISPLAY INVISIBLE (-2873 4050);
FORCEPROP 1 LAST BODY_TYPE PLUMBING
J 2
(-2875 4000);
DISPLAY 1.595745 (-2875 4000);
PAINT GREEN (-2875 4000);
DISPLAY INVISIBLE (-2875 4000);
FORCEPROP 1 LAST HDL_TAP TRUE
J 2
(-3200 3925);
DISPLAY 1.595745 (-3200 3925);
PAINT GREEN (-3200 3925);
DISPLAY INVISIBLE (-3200 3925);
FORCEADD TAP..6
R 2
(-2875 4100);
FORCEPROP 3 LASTPIN (-2925 4100) SIG_NAME M_A_DQS_DP<5>
J 0
(-2915 4110);
DISPLAY 0.659574 (-2915 4110);
PAINT MONO (-2915 4110);
DISPLAY INVISIBLE (-2915 4110);
FORCEPROP 1 LASTPIN (-2925 4100) BN 5
J 2
(-2873 4108);
DISPLAY 0.617021 (-2873 4108);
PAINT PINK (-2873 4108);
FORCEPROP 2 LAST CDS_LIB mstr_standard
J 0
(-2875 4100);
PAINT MONO (-2875 4100);
DISPLAY INVISIBLE (-2875 4100);
FORCEPROP 1 LAST PATH I158
J 2
(-2873 4100);
DISPLAY 0.872340 (-2873 4100);
PAINT GREEN (-2873 4100);
DISPLAY INVISIBLE (-2873 4100);
FORCEPROP 1 LAST BODY_TYPE PLUMBING
J 2
(-2875 4050);
DISPLAY 1.595745 (-2875 4050);
PAINT GREEN (-2875 4050);
DISPLAY INVISIBLE (-2875 4050);
FORCEPROP 1 LAST HDL_TAP TRUE
J 2
(-3200 3975);
DISPLAY 1.595745 (-3200 3975);
PAINT GREEN (-3200 3975);
DISPLAY INVISIBLE (-3200 3975);
FORCEADD TAP..6
R 2
(-2875 4150);
FORCEPROP 3 LASTPIN (-2925 4150) SIG_NAME M_A_DQS_DP<6>
J 0
(-2915 4160);
DISPLAY 0.659574 (-2915 4160);
PAINT MONO (-2915 4160);
DISPLAY INVISIBLE (-2915 4160);
FORCEPROP 1 LASTPIN (-2925 4150) BN 6
J 2
(-2873 4158);
DISPLAY 0.617021 (-2873 4158);
PAINT PINK (-2873 4158);
FORCEPROP 2 LAST CDS_LIB mstr_standard
J 0
(-2875 4150);
PAINT MONO (-2875 4150);
DISPLAY INVISIBLE (-2875 4150);
FORCEPROP 1 LAST PATH I159
J 2
(-2873 4150);
DISPLAY 0.872340 (-2873 4150);
PAINT GREEN (-2873 4150);
DISPLAY INVISIBLE (-2873 4150);
FORCEPROP 1 LAST BODY_TYPE PLUMBING
J 2
(-2875 4100);
DISPLAY 1.595745 (-2875 4100);
PAINT GREEN (-2875 4100);
DISPLAY INVISIBLE (-2875 4100);
FORCEPROP 1 LAST HDL_TAP TRUE
J 2
(-3200 4025);
DISPLAY 1.595745 (-3200 4025);
PAINT GREEN (-3200 4025);
DISPLAY INVISIBLE (-3200 4025);
FORCEADD TAP..6
(-5600 1300);
FORCEPROP 3 LASTPIN (-5550 1300) SIG_NAME M_A_ECC<4>
J 0
(-5540 1310);
DISPLAY 0.659574 (-5540 1310);
PAINT MONO (-5540 1310);
DISPLAY INVISIBLE (-5540 1310);
FORCEPROP 1 LASTPIN (-5550 1300) BN 4
J 0
(-5602 1308);
DISPLAY 0.617021 (-5602 1308);
PAINT PINK (-5602 1308);
FORCEPROP 2 LAST CDS_LIB mstr_standard
J 0
(-5600 1300);
PAINT MONO (-5600 1300);
DISPLAY INVISIBLE (-5600 1300);
FORCEPROP 1 LAST PATH I16
J 0
(-5602 1300);
DISPLAY 0.872340 (-5602 1300);
PAINT GREEN (-5602 1300);
DISPLAY INVISIBLE (-5602 1300);
FORCEPROP 1 LAST BODY_TYPE PLUMBING
J 0
(-5600 1250);
DISPLAY 1.595745 (-5600 1250);
PAINT GREEN (-5600 1250);
DISPLAY INVISIBLE (-5600 1250);
FORCEPROP 1 LAST HDL_TAP TRUE
J 0
(-5275 1175);
DISPLAY 1.595745 (-5275 1175);
PAINT GREEN (-5275 1175);
DISPLAY INVISIBLE (-5275 1175);
FORCEADD TAP..6
R 2
(-2875 4300);
FORCEPROP 3 LASTPIN (-2925 4300) SIG_NAME M_A_DQS_DP<9>
J 0
(-2915 4310);
DISPLAY 0.659574 (-2915 4310);
PAINT MONO (-2915 4310);
DISPLAY INVISIBLE (-2915 4310);
FORCEPROP 1 LASTPIN (-2925 4300) BN 9
J 2
(-2873 4308);
DISPLAY 0.617021 (-2873 4308);
PAINT PINK (-2873 4308);
FORCEPROP 2 LAST CDS_LIB mstr_standard
J 0
(-2875 4300);
PAINT MONO (-2875 4300);
DISPLAY INVISIBLE (-2875 4300);
FORCEPROP 1 LAST PATH I160
J 2
(-2873 4300);
DISPLAY 0.872340 (-2873 4300);
PAINT GREEN (-2873 4300);
DISPLAY INVISIBLE (-2873 4300);
FORCEPROP 1 LAST BODY_TYPE PLUMBING
J 2
(-2875 4250);
DISPLAY 1.595745 (-2875 4250);
PAINT GREEN (-2875 4250);
DISPLAY INVISIBLE (-2875 4250);
FORCEPROP 1 LAST HDL_TAP TRUE
J 2
(-3200 4175);
DISPLAY 1.595745 (-3200 4175);
PAINT GREEN (-3200 4175);
DISPLAY INVISIBLE (-3200 4175);
FORCEADD TAP..6
R 2
(-2875 4250);
FORCEPROP 3 LASTPIN (-2925 4250) SIG_NAME M_A_DQS_DP<8>
J 0
(-2915 4260);
DISPLAY 0.659574 (-2915 4260);
PAINT MONO (-2915 4260);
DISPLAY INVISIBLE (-2915 4260);
FORCEPROP 1 LASTPIN (-2925 4250) BN 8
J 2
(-2873 4258);
DISPLAY 0.617021 (-2873 4258);
PAINT PINK (-2873 4258);
FORCEPROP 2 LAST CDS_LIB mstr_standard
J 0
(-2875 4250);
PAINT MONO (-2875 4250);
DISPLAY INVISIBLE (-2875 4250);
FORCEPROP 1 LAST PATH I161
J 2
(-2873 4250);
DISPLAY 0.872340 (-2873 4250);
PAINT GREEN (-2873 4250);
DISPLAY INVISIBLE (-2873 4250);
FORCEPROP 1 LAST BODY_TYPE PLUMBING
J 2
(-2875 4200);
DISPLAY 1.595745 (-2875 4200);
PAINT GREEN (-2875 4200);
DISPLAY INVISIBLE (-2875 4200);
FORCEPROP 1 LAST HDL_TAP TRUE
J 2
(-3200 4125);
DISPLAY 1.595745 (-3200 4125);
PAINT GREEN (-3200 4125);
DISPLAY INVISIBLE (-3200 4125);
FORCEADD TAP..6
R 2
(-2875 4200);
FORCEPROP 3 LASTPIN (-2925 4200) SIG_NAME M_A_DQS_DP<7>
J 0
(-2915 4210);
DISPLAY 0.659574 (-2915 4210);
PAINT MONO (-2915 4210);
DISPLAY INVISIBLE (-2915 4210);
FORCEPROP 1 LASTPIN (-2925 4200) BN 7
J 2
(-2873 4208);
DISPLAY 0.617021 (-2873 4208);
PAINT PINK (-2873 4208);
FORCEPROP 2 LAST CDS_LIB mstr_standard
J 0
(-2875 4200);
PAINT MONO (-2875 4200);
DISPLAY INVISIBLE (-2875 4200);
FORCEPROP 1 LAST PATH I162
J 2
(-2873 4200);
DISPLAY 0.872340 (-2873 4200);
PAINT GREEN (-2873 4200);
DISPLAY INVISIBLE (-2873 4200);
FORCEPROP 1 LAST BODY_TYPE PLUMBING
J 2
(-2875 4150);
DISPLAY 1.595745 (-2875 4150);
PAINT GREEN (-2875 4150);
DISPLAY INVISIBLE (-2875 4150);
FORCEPROP 1 LAST HDL_TAP TRUE
J 2
(-3200 4075);
DISPLAY 1.595745 (-3200 4075);
PAINT GREEN (-3200 4075);
DISPLAY INVISIBLE (-3200 4075);
FORCEADD TAP..6
R 2
(-2875 4450);
FORCEPROP 3 LASTPIN (-2925 4450) SIG_NAME M_A_DQS_DP<12>
J 0
(-2915 4460);
DISPLAY 0.659574 (-2915 4460);
PAINT MONO (-2915 4460);
DISPLAY INVISIBLE (-2915 4460);
FORCEPROP 1 LASTPIN (-2925 4450) BN 12
J 2
(-2873 4458);
DISPLAY 0.617021 (-2873 4458);
PAINT PINK (-2873 4458);
FORCEPROP 2 LAST CDS_LIB mstr_standard
J 0
(-2875 4450);
PAINT MONO (-2875 4450);
DISPLAY INVISIBLE (-2875 4450);
FORCEPROP 1 LAST PATH I163
J 2
(-2873 4450);
DISPLAY 0.872340 (-2873 4450);
PAINT GREEN (-2873 4450);
DISPLAY INVISIBLE (-2873 4450);
FORCEPROP 1 LAST BODY_TYPE PLUMBING
J 2
(-2875 4400);
DISPLAY 1.595745 (-2875 4400);
PAINT GREEN (-2875 4400);
DISPLAY INVISIBLE (-2875 4400);
FORCEPROP 1 LAST HDL_TAP TRUE
J 2
(-3200 4325);
DISPLAY 1.595745 (-3200 4325);
PAINT GREEN (-3200 4325);
DISPLAY INVISIBLE (-3200 4325);
FORCEADD TAP..6
R 2
(-2875 4500);
FORCEPROP 3 LASTPIN (-2925 4500) SIG_NAME M_A_DQS_DP<13>
J 0
(-2915 4510);
DISPLAY 0.659574 (-2915 4510);
PAINT MONO (-2915 4510);
DISPLAY INVISIBLE (-2915 4510);
FORCEPROP 1 LASTPIN (-2925 4500) BN 13
J 2
(-2873 4508);
DISPLAY 0.617021 (-2873 4508);
PAINT PINK (-2873 4508);
FORCEPROP 2 LAST CDS_LIB mstr_standard
J 0
(-2875 4500);
PAINT MONO (-2875 4500);
DISPLAY INVISIBLE (-2875 4500);
FORCEPROP 1 LAST PATH I164
J 2
(-2873 4500);
DISPLAY 0.872340 (-2873 4500);
PAINT GREEN (-2873 4500);
DISPLAY INVISIBLE (-2873 4500);
FORCEPROP 1 LAST BODY_TYPE PLUMBING
J 2
(-2875 4450);
DISPLAY 1.595745 (-2875 4450);
PAINT GREEN (-2875 4450);
DISPLAY INVISIBLE (-2875 4450);
FORCEPROP 1 LAST HDL_TAP TRUE
J 2
(-3200 4375);
DISPLAY 1.595745 (-3200 4375);
PAINT GREEN (-3200 4375);
DISPLAY INVISIBLE (-3200 4375);
FORCEADD TAP..6
R 2
(-2875 4550);
FORCEPROP 3 LASTPIN (-2925 4550) SIG_NAME M_A_DQS_DP<14>
J 0
(-2915 4560);
DISPLAY 0.659574 (-2915 4560);
PAINT MONO (-2915 4560);
DISPLAY INVISIBLE (-2915 4560);
FORCEPROP 1 LASTPIN (-2925 4550) BN 14
J 2
(-2873 4558);
DISPLAY 0.617021 (-2873 4558);
PAINT PINK (-2873 4558);
FORCEPROP 2 LAST CDS_LIB mstr_standard
J 0
(-2875 4550);
PAINT MONO (-2875 4550);
DISPLAY INVISIBLE (-2875 4550);
FORCEPROP 1 LAST PATH I165
J 2
(-2873 4550);
DISPLAY 0.872340 (-2873 4550);
PAINT GREEN (-2873 4550);
DISPLAY INVISIBLE (-2873 4550);
FORCEPROP 1 LAST BODY_TYPE PLUMBING
J 2
(-2875 4500);
DISPLAY 1.595745 (-2875 4500);
PAINT GREEN (-2875 4500);
DISPLAY INVISIBLE (-2875 4500);
FORCEPROP 1 LAST HDL_TAP TRUE
J 2
(-3200 4425);
DISPLAY 1.595745 (-3200 4425);
PAINT GREEN (-3200 4425);
DISPLAY INVISIBLE (-3200 4425);
FORCEADD TAP..6
R 2
(-2875 4400);
FORCEPROP 3 LASTPIN (-2925 4400) SIG_NAME M_A_DQS_DP<11>
J 0
(-2915 4410);
DISPLAY 0.659574 (-2915 4410);
PAINT MONO (-2915 4410);
DISPLAY INVISIBLE (-2915 4410);
FORCEPROP 1 LASTPIN (-2925 4400) BN 11
J 2
(-2873 4408);
DISPLAY 0.617021 (-2873 4408);
PAINT PINK (-2873 4408);
FORCEPROP 2 LAST CDS_LIB mstr_standard
J 0
(-2875 4400);
PAINT MONO (-2875 4400);
DISPLAY INVISIBLE (-2875 4400);
FORCEPROP 1 LAST PATH I166
J 2
(-2873 4400);
DISPLAY 0.872340 (-2873 4400);
PAINT GREEN (-2873 4400);
DISPLAY INVISIBLE (-2873 4400);
FORCEPROP 1 LAST BODY_TYPE PLUMBING
J 2
(-2875 4350);
DISPLAY 1.595745 (-2875 4350);
PAINT GREEN (-2875 4350);
DISPLAY INVISIBLE (-2875 4350);
FORCEPROP 1 LAST HDL_TAP TRUE
J 2
(-3200 4275);
DISPLAY 1.595745 (-3200 4275);
PAINT GREEN (-3200 4275);
DISPLAY INVISIBLE (-3200 4275);
FORCEADD TAP..6
R 2
(-2875 4350);
FORCEPROP 3 LASTPIN (-2925 4350) SIG_NAME M_A_DQS_DP<10>
J 0
(-2915 4360);
DISPLAY 0.659574 (-2915 4360);
PAINT MONO (-2915 4360);
DISPLAY INVISIBLE (-2915 4360);
FORCEPROP 1 LASTPIN (-2925 4350) BN 10
J 2
(-2873 4358);
DISPLAY 0.617021 (-2873 4358);
PAINT PINK (-2873 4358);
FORCEPROP 2 LAST CDS_LIB mstr_standard
J 0
(-2875 4350);
PAINT MONO (-2875 4350);
DISPLAY INVISIBLE (-2875 4350);
FORCEPROP 1 LAST PATH I167
J 2
(-2873 4350);
DISPLAY 0.872340 (-2873 4350);
PAINT GREEN (-2873 4350);
DISPLAY INVISIBLE (-2873 4350);
FORCEPROP 1 LAST BODY_TYPE PLUMBING
J 2
(-2875 4300);
DISPLAY 1.595745 (-2875 4300);
PAINT GREEN (-2875 4300);
DISPLAY INVISIBLE (-2875 4300);
FORCEPROP 1 LAST HDL_TAP TRUE
J 2
(-3200 4225);
DISPLAY 1.595745 (-3200 4225);
PAINT GREEN (-3200 4225);
DISPLAY INVISIBLE (-3200 4225);
FORCEADD TAP..6
R 2
(-2875 4700);
FORCEPROP 3 LASTPIN (-2925 4700) SIG_NAME M_A_DQS_DP<17>
J 0
(-2915 4710);
DISPLAY 0.659574 (-2915 4710);
PAINT MONO (-2915 4710);
DISPLAY INVISIBLE (-2915 4710);
FORCEPROP 1 LASTPIN (-2925 4700) BN 17
J 2
(-2873 4708);
DISPLAY 0.617021 (-2873 4708);
PAINT PINK (-2873 4708);
FORCEPROP 2 LAST CDS_LIB mstr_standard
J 2
(-2875 4700);
PAINT MONO (-2875 4700);
DISPLAY INVISIBLE (-2875 4700);
FORCEPROP 1 LAST PATH I168
J 2
(-2873 4700);
DISPLAY 0.872340 (-2873 4700);
PAINT GREEN (-2873 4700);
DISPLAY INVISIBLE (-2873 4700);
FORCEPROP 1 LAST BODY_TYPE PLUMBING
J 2
(-2875 4650);
DISPLAY 1.595745 (-2875 4650);
PAINT GREEN (-2875 4650);
DISPLAY INVISIBLE (-2875 4650);
FORCEPROP 1 LAST HDL_TAP TRUE
J 2
(-3200 4575);
DISPLAY 1.595745 (-3200 4575);
PAINT GREEN (-3200 4575);
DISPLAY INVISIBLE (-3200 4575);
FORCEADD TAP..6
R 2
(-2875 4600);
FORCEPROP 3 LASTPIN (-2925 4600) SIG_NAME M_A_DQS_DP<15>
J 0
(-2915 4610);
DISPLAY 0.659574 (-2915 4610);
PAINT MONO (-2915 4610);
DISPLAY INVISIBLE (-2915 4610);
FORCEPROP 1 LASTPIN (-2925 4600) BN 15
J 2
(-2873 4608);
DISPLAY 0.617021 (-2873 4608);
PAINT PINK (-2873 4608);
FORCEPROP 2 LAST CDS_LIB mstr_standard
J 0
(-2875 4600);
PAINT MONO (-2875 4600);
DISPLAY INVISIBLE (-2875 4600);
FORCEPROP 1 LAST PATH I169
J 2
(-2873 4600);
DISPLAY 0.872340 (-2873 4600);
PAINT GREEN (-2873 4600);
DISPLAY INVISIBLE (-2873 4600);
FORCEPROP 1 LAST BODY_TYPE PLUMBING
J 2
(-2875 4550);
DISPLAY 1.595745 (-2875 4550);
PAINT GREEN (-2875 4550);
DISPLAY INVISIBLE (-2875 4550);
FORCEPROP 1 LAST HDL_TAP TRUE
J 2
(-3200 4475);
DISPLAY 1.595745 (-3200 4475);
PAINT GREEN (-3200 4475);
DISPLAY INVISIBLE (-3200 4475);
FORCEADD TAP..6
(-5600 1250);
FORCEPROP 3 LASTPIN (-5550 1250) SIG_NAME M_A_ECC<3>
J 0
(-5540 1260);
DISPLAY 0.659574 (-5540 1260);
PAINT MONO (-5540 1260);
DISPLAY INVISIBLE (-5540 1260);
FORCEPROP 1 LASTPIN (-5550 1250) BN 3
J 0
(-5602 1258);
DISPLAY 0.617021 (-5602 1258);
PAINT PINK (-5602 1258);
FORCEPROP 2 LAST CDS_LIB mstr_standard
J 0
(-5600 1250);
PAINT MONO (-5600 1250);
DISPLAY INVISIBLE (-5600 1250);
FORCEPROP 1 LAST PATH I17
J 0
(-5602 1250);
DISPLAY 0.872340 (-5602 1250);
PAINT GREEN (-5602 1250);
DISPLAY INVISIBLE (-5602 1250);
FORCEPROP 1 LAST BODY_TYPE PLUMBING
J 0
(-5600 1200);
DISPLAY 1.595745 (-5600 1200);
PAINT GREEN (-5600 1200);
DISPLAY INVISIBLE (-5600 1200);
FORCEPROP 1 LAST HDL_TAP TRUE
J 0
(-5275 1125);
DISPLAY 1.595745 (-5275 1125);
PAINT GREEN (-5275 1125);
DISPLAY INVISIBLE (-5275 1125);
FORCEADD TAP..6
R 2
(-2875 4650);
FORCEPROP 3 LASTPIN (-2925 4650) SIG_NAME M_A_DQS_DP<16>
J 0
(-2915 4660);
DISPLAY 0.659574 (-2915 4660);
PAINT MONO (-2915 4660);
DISPLAY INVISIBLE (-2915 4660);
FORCEPROP 1 LASTPIN (-2925 4650) BN 16
J 2
(-2873 4658);
DISPLAY 0.617021 (-2873 4658);
PAINT PINK (-2873 4658);
FORCEPROP 2 LAST CDS_LIB mstr_standard
J 0
(-2875 4650);
PAINT MONO (-2875 4650);
DISPLAY INVISIBLE (-2875 4650);
FORCEPROP 1 LAST PATH I170
J 2
(-2873 4650);
DISPLAY 0.872340 (-2873 4650);
PAINT GREEN (-2873 4650);
DISPLAY INVISIBLE (-2873 4650);
FORCEPROP 1 LAST BODY_TYPE PLUMBING
J 2
(-2875 4600);
DISPLAY 1.595745 (-2875 4600);
PAINT GREEN (-2875 4600);
DISPLAY INVISIBLE (-2875 4600);
FORCEPROP 1 LAST HDL_TAP TRUE
J 2
(-3200 4525);
DISPLAY 1.595745 (-3200 4525);
PAINT GREEN (-3200 4525);
DISPLAY INVISIBLE (-3200 4525);
FORCEADD OFFPAGE..3
(-2025 4775);
FORCEPROP 2 LAST $XR1 44 
J 0
(-1721 4775);
DISPLAY 0.638298 (-1721 4775);
PAINT MONO (-1721 4775);
FORCEPROP 2 LAST $XR0 43 
J 0
(-1811 4775);
DISPLAY 0.638298 (-1811 4775);
PAINT MONO (-1811 4775);
FORCEPROP 2 LAST CDS_LIB mstr_standard
J 0
(-2025 4775);
PAINT MONO (-2025 4775);
DISPLAY INVISIBLE (-2025 4775);
FORCEPROP 2 LAST PATH I171
J 0
(-1825 4850);
DISPLAY 1.021277 (-1825 4850);
PAINT ORANGE (-1825 4850);
DISPLAY INVISIBLE (-1825 4850);
FORCEPROP 1 LAST OFFPAGE TRUE
J 0
(-1700 4650);
DISPLAY 1.170213 (-1700 4650);
PAINT GREEN (-1700 4650);
DISPLAY INVISIBLE (-1700 4650);
FORCEPROP 1 LAST COMMENT_BODY TRUE
J 0
(-2075 4675);
DISPLAY 1.170213 (-2075 4675);
PAINT GREEN (-2075 4675);
DISPLAY INVISIBLE (-2075 4675);
FORCEADD SKX_EXT_B..3
(-4200 2600);
FORCEPROP 1 LAST LOCATION U5D1
J 0
(-5000 4950);
DISPLAY 0.617021 (-5000 4950);
PAINT AQUA (-5000 4950);
FORCEPROP 1 LAST PART_NUMBER TBD
J 0
(-5000 350);
DISPLAY 0.617021 (-5000 350);
PAINT BLUE (-5000 350);
FORCEPROP 1 LAST MATERIAL IC
J 0
(-5000 4900);
DISPLAY 0.617021 (-5000 4900);
PAINT SKYBLUE (-5000 4900);
FORCEPROP 2 LASTPIN (-3350 550) $PN D53
J 0
(-3340 560);
DISPLAY 0.617021 (-3340 560);
PAINT ORANGE (-3340 560);
FORCEPROP 2 LASTPIN (-3350 1600) $PN G48
J 0
(-3340 1610);
DISPLAY 0.617021 (-3340 1610);
PAINT ORANGE (-3340 1610);
FORCEPROP 2 LASTPIN (-3350 1550) $PN G50
J 0
(-3340 1560);
DISPLAY 0.617021 (-3340 1560);
PAINT ORANGE (-3340 1560);
FORCEPROP 2 LASTPIN (-3350 1500) $PN C48
J 0
(-3340 1510);
DISPLAY 0.617021 (-3340 1510);
PAINT ORANGE (-3340 1510);
FORCEPROP 2 LASTPIN (-3350 1450) $PN C50
J 0
(-3340 1460);
DISPLAY 0.617021 (-3340 1460);
PAINT ORANGE (-3340 1460);
FORCEPROP 2 LASTPIN (-3350 2800) $PN K47
J 0
(-3340 2810);
DISPLAY 0.617021 (-3340 2810);
PAINT ORANGE (-3340 2810);
FORCEPROP 2 LASTPIN (-3350 2750) $PN D51
J 0
(-3340 2760);
DISPLAY 0.617021 (-3340 2760);
PAINT ORANGE (-3340 2760);
FORCEPROP 2 LASTPIN (-3350 2700) $PN K49
J 0
(-3340 2710);
DISPLAY 0.617021 (-3340 2710);
PAINT ORANGE (-3340 2710);
FORCEPROP 2 LASTPIN (-3350 2650) $PN F51
J 0
(-3340 2660);
DISPLAY 0.617021 (-3340 2660);
PAINT ORANGE (-3340 2660);
FORCEPROP 2 LASTPIN (-3350 2600) $PN J48
J 0
(-3340 2610);
DISPLAY 0.617021 (-3340 2610);
PAINT ORANGE (-3340 2610);
FORCEPROP 2 LASTPIN (-3350 2550) $PN J64
J 0
(-3340 2560);
DISPLAY 0.617021 (-3340 2560);
PAINT ORANGE (-3340 2560);
FORCEPROP 2 LASTPIN (-3350 2500) $PN G62
J 0
(-3340 2510);
DISPLAY 0.617021 (-3340 2510);
PAINT ORANGE (-3340 2510);
FORCEPROP 2 LASTPIN (-3350 2450) $PN J54
J 0
(-3340 2460);
DISPLAY 0.617021 (-3340 2460);
PAINT ORANGE (-3340 2460);
FORCEPROP 2 LASTPIN (-3350 2400) $PN F61
J 0
(-3340 2410);
DISPLAY 0.617021 (-3340 2410);
PAINT ORANGE (-3340 2410);
FORCEPROP 2 LASTPIN (-3350 2350) $PN C60
J 0
(-3340 2360);
DISPLAY 0.617021 (-3340 2360);
PAINT ORANGE (-3340 2360);
FORCEPROP 2 LASTPIN (-3350 2300) $PN G60
J 0
(-3340 2310);
DISPLAY 0.617021 (-3340 2310);
PAINT ORANGE (-3340 2310);
FORCEPROP 2 LASTPIN (-3350 2250) $PN D59
J 0
(-3340 2260);
DISPLAY 0.617021 (-3340 2260);
PAINT ORANGE (-3340 2260);
FORCEPROP 2 LASTPIN (-3350 2200) $PN F59
J 0
(-3340 2210);
DISPLAY 0.617021 (-3340 2210);
PAINT ORANGE (-3340 2210);
FORCEPROP 2 LASTPIN (-3350 2150) $PN G58
J 0
(-3340 2160);
DISPLAY 0.617021 (-3340 2160);
PAINT ORANGE (-3340 2160);
FORCEPROP 2 LASTPIN (-3350 2100) $PN C58
J 0
(-3340 2110);
DISPLAY 0.617021 (-3340 2110);
PAINT ORANGE (-3340 2110);
FORCEPROP 2 LASTPIN (-3350 2050) $PN D57
J 0
(-3340 2060);
DISPLAY 0.617021 (-3340 2060);
PAINT ORANGE (-3340 2060);
FORCEPROP 2 LASTPIN (-3350 2000) $PN F57
J 0
(-3340 2010);
DISPLAY 0.617021 (-3340 2010);
PAINT ORANGE (-3340 2010);
FORCEPROP 2 LASTPIN (-3350 1950) $PN F53
J 0
(-3340 1960);
DISPLAY 0.617021 (-3340 1960);
PAINT ORANGE (-3340 1960);
FORCEPROP 2 LASTPIN (-5050 1450) $PN AG66
J 2
(-5060 1460);
DISPLAY 0.617021 (-5060 1460);
PAINT ORANGE (-5060 1460);
FORCEPROP 2 LASTPIN (-5050 1400) $PN AC66
J 2
(-5060 1410);
DISPLAY 0.617021 (-5060 1410);
PAINT ORANGE (-5060 1410);
FORCEPROP 2 LASTPIN (-5050 1350) $PN AF69
J 2
(-5060 1360);
DISPLAY 0.617021 (-5060 1360);
PAINT ORANGE (-5060 1360);
FORCEPROP 2 LASTPIN (-5050 1300) $PN AD69
J 2
(-5060 1310);
DISPLAY 0.617021 (-5060 1310);
PAINT ORANGE (-5060 1310);
FORCEPROP 2 LASTPIN (-5050 1250) $PN AF65
J 2
(-5060 1260);
DISPLAY 0.617021 (-5060 1260);
PAINT ORANGE (-5060 1260);
FORCEPROP 2 LASTPIN (-5050 1200) $PN AD65
J 2
(-5060 1210);
DISPLAY 0.617021 (-5060 1210);
PAINT ORANGE (-5060 1210);
FORCEPROP 2 LASTPIN (-5050 1150) $PN AG68
J 2
(-5060 1160);
DISPLAY 0.617021 (-5060 1160);
PAINT ORANGE (-5060 1160);
FORCEPROP 2 LASTPIN (-5050 1100) $PN AC68
J 2
(-5060 1110);
DISPLAY 0.617021 (-5060 1110);
PAINT ORANGE (-5060 1110);
FORCEPROP 2 LASTPIN (-3350 4700) $PN AD67
J 0
(-3340 4710);
DISPLAY 0.617021 (-3340 4710);
PAINT ORANGE (-3340 4710);
FORCEPROP 2 LASTPIN (-3350 4650) $PN L24
J 0
(-3340 4660);
DISPLAY 0.617021 (-3340 4660);
PAINT ORANGE (-3340 4660);
FORCEPROP 2 LASTPIN (-3350 4600) $PN L30
J 0
(-3340 4610);
DISPLAY 0.617021 (-3340 4610);
PAINT ORANGE (-3340 4610);
FORCEPROP 2 LASTPIN (-3350 4550) $PN L36
J 0
(-3340 4560);
DISPLAY 0.617021 (-3340 4560);
PAINT ORANGE (-3340 4560);
FORCEPROP 2 LASTPIN (-3350 4500) $PN C40
J 0
(-3340 4510);
DISPLAY 0.617021 (-3340 4510);
PAINT ORANGE (-3340 4510);
FORCEPROP 2 LASTPIN (-3350 4450) $PN M75
J 0
(-3340 4460);
DISPLAY 0.617021 (-3340 4460);
PAINT ORANGE (-3340 4460);
FORCEPROP 2 LASTPIN (-3350 4400) $PN T81
J 0
(-3340 4410);
DISPLAY 0.617021 (-3340 4410);
PAINT ORANGE (-3340 4410);
FORCEPROP 2 LASTPIN (-3350 4350) $PN V85
J 0
(-3340 4360);
DISPLAY 0.617021 (-3340 4360);
PAINT ORANGE (-3340 4360);
FORCEPROP 2 LASTPIN (-3350 4300) $PN AM85
J 0
(-3340 4310);
DISPLAY 0.617021 (-3340 4310);
PAINT ORANGE (-3340 4310);
FORCEPROP 2 LASTPIN (-3350 4250) $PN AF67
J 0
(-3340 4260);
DISPLAY 0.617021 (-3340 4260);
PAINT ORANGE (-3340 4260);
FORCEPROP 2 LASTPIN (-3350 4200) $PN R24
J 0
(-3340 4210);
DISPLAY 0.617021 (-3340 4210);
PAINT ORANGE (-3340 4210);
FORCEPROP 2 LASTPIN (-3350 4150) $PN N30
J 0
(-3340 4160);
DISPLAY 0.617021 (-3340 4160);
PAINT ORANGE (-3340 4160);
FORCEPROP 2 LASTPIN (-3350 4100) $PN N36
J 0
(-3340 4110);
DISPLAY 0.617021 (-3340 4110);
PAINT ORANGE (-3340 4110);
FORCEPROP 2 LASTPIN (-3350 4050) $PN E40
J 0
(-3340 4060);
DISPLAY 0.617021 (-3340 4060);
PAINT ORANGE (-3340 4060);
FORCEPROP 2 LASTPIN (-3350 4000) $PN P75
J 0
(-3340 4010);
DISPLAY 0.617021 (-3340 4010);
PAINT ORANGE (-3340 4010);
FORCEPROP 2 LASTPIN (-3350 3950) $PN R80
J 0
(-3340 3960);
DISPLAY 0.617021 (-3340 3960);
PAINT ORANGE (-3340 3960);
FORCEPROP 2 LASTPIN (-3350 3900) $PN P85
J 0
(-3340 3910);
DISPLAY 0.617021 (-3340 3910);
PAINT ORANGE (-3340 3910);
FORCEPROP 2 LASTPIN (-3350 3850) $PN AH85
J 0
(-3340 3860);
DISPLAY 0.617021 (-3340 3860);
PAINT ORANGE (-3340 3860);
FORCEPROP 2 LASTPIN (-3350 3750) $PN AB67
J 0
(-3340 3760);
DISPLAY 0.617021 (-3340 3760);
PAINT ORANGE (-3340 3760);
FORCEPROP 2 LASTPIN (-3350 3700) $PN J24
J 0
(-3340 3710);
DISPLAY 0.617021 (-3340 3710);
PAINT ORANGE (-3340 3710);
FORCEPROP 2 LASTPIN (-3350 3650) $PN J30
J 0
(-3340 3660);
DISPLAY 0.617021 (-3340 3660);
PAINT ORANGE (-3340 3660);
FORCEPROP 2 LASTPIN (-3350 3600) $PN J36
J 0
(-3340 3610);
DISPLAY 0.617021 (-3340 3610);
PAINT ORANGE (-3340 3610);
FORCEPROP 2 LASTPIN (-3350 3550) $PN A40
J 0
(-3340 3560);
DISPLAY 0.617021 (-3340 3560);
PAINT ORANGE (-3340 3560);
FORCEPROP 2 LASTPIN (-3350 3500) $PN K75
J 0
(-3340 3510);
DISPLAY 0.617021 (-3340 3510);
PAINT ORANGE (-3340 3510);
FORCEPROP 2 LASTPIN (-3350 3450) $PN U82
J 0
(-3340 3460);
DISPLAY 0.617021 (-3340 3460);
PAINT ORANGE (-3340 3460);
FORCEPROP 2 LASTPIN (-3350 3400) $PN U84
J 0
(-3340 3410);
DISPLAY 0.617021 (-3340 3410);
PAINT ORANGE (-3340 3410);
FORCEPROP 2 LASTPIN (-3350 3350) $PN AL84
J 0
(-3340 3360);
DISPLAY 0.617021 (-3340 3360);
PAINT ORANGE (-3340 3360);
FORCEPROP 2 LASTPIN (-3350 3300) $PN AH67
J 0
(-3340 3310);
DISPLAY 0.617021 (-3340 3310);
PAINT ORANGE (-3340 3310);
FORCEPROP 2 LASTPIN (-3350 3250) $PN N24
J 0
(-3340 3260);
DISPLAY 0.617021 (-3340 3260);
PAINT ORANGE (-3340 3260);
FORCEPROP 2 LASTPIN (-3350 3200) $PN R30
J 0
(-3340 3210);
DISPLAY 0.617021 (-3340 3210);
PAINT ORANGE (-3340 3210);
FORCEPROP 2 LASTPIN (-3350 3150) $PN R36
J 0
(-3340 3160);
DISPLAY 0.617021 (-3340 3160);
PAINT ORANGE (-3340 3160);
FORCEPROP 2 LASTPIN (-3350 3100) $PN G40
J 0
(-3340 3110);
DISPLAY 0.617021 (-3340 3110);
PAINT ORANGE (-3340 3110);
FORCEPROP 2 LASTPIN (-3350 3050) $PN T75
J 0
(-3340 3060);
DISPLAY 0.617021 (-3340 3060);
PAINT ORANGE (-3340 3060);
FORCEPROP 2 LASTPIN (-3350 3000) $PN P79
J 0
(-3340 3010);
DISPLAY 0.617021 (-3340 3010);
PAINT ORANGE (-3340 3010);
FORCEPROP 2 LASTPIN (-3350 2950) $PN R84
J 0
(-3340 2960);
DISPLAY 0.617021 (-3340 2960);
PAINT ORANGE (-3340 2960);
FORCEPROP 2 LASTPIN (-3350 2900) $PN AJ84
J 0
(-3340 2910);
DISPLAY 0.617021 (-3340 2910);
PAINT ORANGE (-3340 2910);
FORCEPROP 2 LASTPIN (-5050 4700) $PN K23
J 2
(-5060 4710);
DISPLAY 0.617021 (-5060 4710);
PAINT ORANGE (-5060 4710);
FORCEPROP 2 LASTPIN (-5050 4650) $PN H23
J 2
(-5060 4660);
DISPLAY 0.617021 (-5060 4660);
PAINT ORANGE (-5060 4660);
FORCEPROP 2 LASTPIN (-5050 4600) $PN N26
J 2
(-5060 4610);
DISPLAY 0.617021 (-5060 4610);
PAINT ORANGE (-5060 4610);
FORCEPROP 2 LASTPIN (-5050 4550) $PN L26
J 2
(-5060 4560);
DISPLAY 0.617021 (-5060 4560);
PAINT ORANGE (-5060 4560);
FORCEPROP 2 LASTPIN (-5050 4500) $PN T23
J 2
(-5060 4510);
DISPLAY 0.617021 (-5060 4510);
PAINT ORANGE (-5060 4510);
FORCEPROP 2 LASTPIN (-5050 4450) $PN P23
J 2
(-5060 4460);
DISPLAY 0.617021 (-5060 4460);
PAINT ORANGE (-5060 4460);
FORCEPROP 2 LASTPIN (-5050 4400) $PN P25
J 2
(-5060 4410);
DISPLAY 0.617021 (-5060 4410);
PAINT ORANGE (-5060 4410);
FORCEPROP 2 LASTPIN (-5050 4350) $PN K25
J 2
(-5060 4360);
DISPLAY 0.617021 (-5060 4360);
PAINT ORANGE (-5060 4360);
FORCEPROP 2 LASTPIN (-5050 4300) $PN P29
J 2
(-5060 4310);
DISPLAY 0.617021 (-5060 4310);
PAINT ORANGE (-5060 4310);
FORCEPROP 2 LASTPIN (-5050 4250) $PN K29
J 2
(-5060 4260);
DISPLAY 0.617021 (-5060 4260);
PAINT ORANGE (-5060 4260);
FORCEPROP 2 LASTPIN (-5050 4200) $PN N32
J 2
(-5060 4210);
DISPLAY 0.617021 (-5060 4210);
PAINT ORANGE (-5060 4210);
FORCEPROP 2 LASTPIN (-5050 4150) $PN L32
J 2
(-5060 4160);
DISPLAY 0.617021 (-5060 4160);
PAINT ORANGE (-5060 4160);
FORCEPROP 2 LASTPIN (-5050 4100) $PN N28
J 2
(-5060 4110);
DISPLAY 0.617021 (-5060 4110);
PAINT ORANGE (-5060 4110);
FORCEPROP 2 LASTPIN (-5050 4050) $PN L28
J 2
(-5060 4060);
DISPLAY 0.617021 (-5060 4060);
PAINT ORANGE (-5060 4060);
FORCEPROP 2 LASTPIN (-5050 4000) $PN P31
J 2
(-5060 4010);
DISPLAY 0.617021 (-5060 4010);
PAINT ORANGE (-5060 4010);
FORCEPROP 2 LASTPIN (-5050 3950) $PN K31
J 2
(-5060 3960);
DISPLAY 0.617021 (-5060 3960);
PAINT ORANGE (-5060 3960);
FORCEPROP 2 LASTPIN (-5050 3900) $PN P35
J 2
(-5060 3910);
DISPLAY 0.617021 (-5060 3910);
PAINT ORANGE (-5060 3910);
FORCEPROP 2 LASTPIN (-5050 3850) $PN K35
J 2
(-5060 3860);
DISPLAY 0.617021 (-5060 3860);
PAINT ORANGE (-5060 3860);
FORCEPROP 2 LASTPIN (-5050 3800) $PN N38
J 2
(-5060 3810);
DISPLAY 0.617021 (-5060 3810);
PAINT ORANGE (-5060 3810);
FORCEPROP 2 LASTPIN (-5050 3750) $PN L38
J 2
(-5060 3760);
DISPLAY 0.617021 (-5060 3760);
PAINT ORANGE (-5060 3760);
FORCEPROP 2 LASTPIN (-5050 3700) $PN N34
J 2
(-5060 3710);
DISPLAY 0.617021 (-5060 3710);
PAINT ORANGE (-5060 3710);
FORCEPROP 2 LASTPIN (-5050 3650) $PN L34
J 2
(-5060 3660);
DISPLAY 0.617021 (-5060 3660);
PAINT ORANGE (-5060 3660);
FORCEPROP 2 LASTPIN (-5050 3600) $PN P37
J 2
(-5060 3610);
DISPLAY 0.617021 (-5060 3610);
PAINT ORANGE (-5060 3610);
FORCEPROP 2 LASTPIN (-5050 3550) $PN K37
J 2
(-5060 3560);
DISPLAY 0.617021 (-5060 3560);
PAINT ORANGE (-5060 3560);
FORCEPROP 2 LASTPIN (-5050 3500) $PN F39
J 2
(-5060 3510);
DISPLAY 0.617021 (-5060 3510);
PAINT ORANGE (-5060 3510);
FORCEPROP 2 LASTPIN (-5050 3450) $PN B39
J 2
(-5060 3460);
DISPLAY 0.617021 (-5060 3460);
PAINT ORANGE (-5060 3460);
FORCEPROP 2 LASTPIN (-5050 3400) $PN F41
J 2
(-5060 3410);
DISPLAY 0.617021 (-5060 3410);
PAINT ORANGE (-5060 3410);
FORCEPROP 2 LASTPIN (-5050 3350) $PN E42
J 2
(-5060 3360);
DISPLAY 0.617021 (-5060 3360);
PAINT ORANGE (-5060 3360);
FORCEPROP 2 LASTPIN (-5050 3300) $PN E38
J 2
(-5060 3310);
DISPLAY 0.617021 (-5060 3310);
PAINT ORANGE (-5060 3310);
FORCEPROP 2 LASTPIN (-5050 3250) $PN C38
J 2
(-5060 3260);
DISPLAY 0.617021 (-5060 3260);
PAINT ORANGE (-5060 3260);
FORCEPROP 2 LASTPIN (-5050 3200) $PN B41
J 2
(-5060 3210);
DISPLAY 0.617021 (-5060 3210);
PAINT ORANGE (-5060 3210);
FORCEPROP 2 LASTPIN (-5050 3150) $PN C42
J 2
(-5060 3160);
DISPLAY 0.617021 (-5060 3160);
PAINT ORANGE (-5060 3160);
FORCEPROP 2 LASTPIN (-5050 3100) $PN R74
J 2
(-5060 3110);
DISPLAY 0.617021 (-5060 3110);
PAINT ORANGE (-5060 3110);
FORCEPROP 2 LASTPIN (-5050 3050) $PN L74
J 2
(-5060 3060);
DISPLAY 0.617021 (-5060 3060);
PAINT ORANGE (-5060 3060);
FORCEPROP 2 LASTPIN (-5050 3000) $PN P77
J 2
(-5060 3010);
DISPLAY 0.617021 (-5060 3010);
PAINT ORANGE (-5060 3010);
FORCEPROP 2 LASTPIN (-5050 2850) $PN M73
J 2
(-5060 2860);
DISPLAY 0.617021 (-5060 2860);
PAINT ORANGE (-5060 2860);
FORCEPROP 2 LASTPIN (-5050 2800) $PN R76
J 2
(-5060 2810);
DISPLAY 0.617021 (-5060 2810);
PAINT ORANGE (-5060 2810);
FORCEPROP 2 LASTPIN (-5050 2750) $PN L76
J 2
(-5060 2760);
DISPLAY 0.617021 (-5060 2760);
PAINT ORANGE (-5060 2760);
FORCEPROP 2 LASTPIN (-5050 2700) $PN N80
J 2
(-5060 2710);
DISPLAY 0.617021 (-5060 2710);
PAINT ORANGE (-5060 2710);
FORCEPROP 2 LASTPIN (-5050 2650) $PN R82
J 2
(-5060 2660);
DISPLAY 0.617021 (-5060 2660);
PAINT ORANGE (-5060 2660);
FORCEPROP 2 LASTPIN (-5050 2600) $PN V79
J 2
(-5060 2610);
DISPLAY 0.617021 (-5060 2610);
PAINT ORANGE (-5060 2610);
FORCEPROP 2 LASTPIN (-5050 2550) $PN W80
J 2
(-5060 2560);
DISPLAY 0.617021 (-5060 2560);
PAINT ORANGE (-5060 2560);
FORCEPROP 2 LASTPIN (-5050 2500) $PN M81
J 2
(-5060 2510);
DISPLAY 0.617021 (-5060 2510);
PAINT ORANGE (-5060 2510);
FORCEPROP 2 LASTPIN (-5050 2450) $PN N82
J 2
(-5060 2460);
DISPLAY 0.617021 (-5060 2460);
PAINT ORANGE (-5060 2460);
FORCEPROP 2 LASTPIN (-5050 2400) $PN T79
J 2
(-5060 2410);
DISPLAY 0.617021 (-5060 2410);
PAINT ORANGE (-5060 2410);
FORCEPROP 2 LASTPIN (-5050 2350) $PN V81
J 2
(-5060 2360);
DISPLAY 0.617021 (-5060 2360);
PAINT ORANGE (-5060 2360);
FORCEPROP 2 LASTPIN (-5050 2300) $PN N84
J 2
(-5060 2310);
DISPLAY 0.617021 (-5060 2310);
PAINT ORANGE (-5060 2310);
FORCEPROP 2 LASTPIN (-5050 2250) $PN N86
J 2
(-5060 2260);
DISPLAY 0.617021 (-5060 2260);
PAINT ORANGE (-5060 2260);
FORCEPROP 2 LASTPIN (-5050 2200) $PN AA84
J 2
(-5060 2210);
DISPLAY 0.617021 (-5060 2210);
PAINT ORANGE (-5060 2210);
FORCEPROP 2 LASTPIN (-5050 2150) $PN AA86
J 2
(-5060 2160);
DISPLAY 0.617021 (-5060 2160);
PAINT ORANGE (-5060 2160);
FORCEPROP 2 LASTPIN (-5050 2100) $PN L84
J 2
(-5060 2110);
DISPLAY 0.617021 (-5060 2110);
PAINT ORANGE (-5060 2110);
FORCEPROP 2 LASTPIN (-5050 2050) $PN L86
J 2
(-5060 2060);
DISPLAY 0.617021 (-5060 2060);
PAINT ORANGE (-5060 2060);
FORCEPROP 2 LASTPIN (-5050 2000) $PN W84
J 2
(-5060 2010);
DISPLAY 0.617021 (-5060 2010);
PAINT ORANGE (-5060 2010);
FORCEPROP 2 LASTPIN (-5050 1950) $PN W86
J 2
(-5060 1960);
DISPLAY 0.617021 (-5060 1960);
PAINT ORANGE (-5060 1960);
FORCEPROP 2 LASTPIN (-5050 1900) $PN AG84
J 2
(-5060 1910);
DISPLAY 0.617021 (-5060 1910);
PAINT ORANGE (-5060 1910);
FORCEPROP 2 LASTPIN (-5050 1850) $PN AG86
J 2
(-5060 1860);
DISPLAY 0.617021 (-5060 1860);
PAINT ORANGE (-5060 1860);
FORCEPROP 2 LASTPIN (-5050 1800) $PN AR84
J 2
(-5060 1810);
DISPLAY 0.617021 (-5060 1810);
PAINT ORANGE (-5060 1810);
FORCEPROP 2 LASTPIN (-5050 1750) $PN AR86
J 2
(-5060 1760);
DISPLAY 0.617021 (-5060 1760);
PAINT ORANGE (-5060 1760);
FORCEPROP 2 LASTPIN (-5050 1700) $PN AE84
J 2
(-5060 1710);
DISPLAY 0.617021 (-5060 1710);
PAINT ORANGE (-5060 1710);
FORCEPROP 2 LASTPIN (-5050 1650) $PN AE86
J 2
(-5060 1660);
DISPLAY 0.617021 (-5060 1660);
PAINT ORANGE (-5060 1660);
FORCEPROP 2 LASTPIN (-5050 1600) $PN AN84
J 2
(-5060 1610);
DISPLAY 0.617021 (-5060 1610);
PAINT ORANGE (-5060 1610);
FORCEPROP 2 LASTPIN (-5050 1550) $PN AN86
J 2
(-5060 1560);
DISPLAY 0.617021 (-5060 1560);
PAINT ORANGE (-5060 1560);
FORCEPROP 2 LASTPIN (-3350 1350) $PN K45
J 0
(-3340 1360);
DISPLAY 0.617021 (-3340 1360);
PAINT ORANGE (-3340 1360);
FORCEPROP 2 LASTPIN (-3350 1300) $PN F45
J 0
(-3340 1310);
DISPLAY 0.617021 (-3340 1310);
PAINT ORANGE (-3340 1310);
FORCEPROP 2 LASTPIN (-3350 1250) $PN D49
J 0
(-3340 1260);
DISPLAY 0.617021 (-3340 1260);
PAINT ORANGE (-3340 1260);
FORCEPROP 2 LASTPIN (-3350 1200) $PN B51
J 0
(-3340 1210);
DISPLAY 0.617021 (-3340 1210);
PAINT ORANGE (-3340 1210);
FORCEPROP 2 LASTPIN (-3350 1150) $PN F47
J 0
(-3340 1160);
DISPLAY 0.617021 (-3340 1160);
PAINT ORANGE (-3340 1160);
FORCEPROP 2 LASTPIN (-3350 1100) $PN D47
J 0
(-3340 1110);
DISPLAY 0.617021 (-3340 1110);
PAINT ORANGE (-3340 1110);
FORCEPROP 2 LASTPIN (-3350 1050) $PN F49
J 0
(-3340 1060);
DISPLAY 0.617021 (-3340 1060);
PAINT ORANGE (-3340 1060);
FORCEPROP 2 LASTPIN (-3350 1000) $PN G52
J 0
(-3340 1010);
DISPLAY 0.617021 (-3340 1010);
PAINT ORANGE (-3340 1010);
FORCEPROP 2 LASTPIN (-5050 1000) $PN B57
J 2
(-5060 1010);
DISPLAY 0.617021 (-5060 1010);
PAINT ORANGE (-5060 1010);
FORCEPROP 2 LASTPIN (-5050 950) $PN G56
J 2
(-5060 960);
DISPLAY 0.617021 (-5060 960);
PAINT ORANGE (-5060 960);
FORCEPROP 2 LASTPIN (-5050 900) $PN B55
J 2
(-5060 910);
DISPLAY 0.617021 (-5060 910);
PAINT ORANGE (-5060 910);
FORCEPROP 2 LASTPIN (-5050 850) $PN D55
J 2
(-5060 860);
DISPLAY 0.617021 (-5060 860);
PAINT ORANGE (-5060 860);
FORCEPROP 2 LASTPIN (-5050 800) $PN C56
J 2
(-5060 810);
DISPLAY 0.617021 (-5060 810);
PAINT ORANGE (-5060 810);
FORCEPROP 2 LASTPIN (-5050 750) $PN J56
J 2
(-5060 760);
DISPLAY 0.617021 (-5060 760);
PAINT ORANGE (-5060 760);
FORCEPROP 2 LASTPIN (-5050 700) $PN C54
J 2
(-5060 710);
DISPLAY 0.617021 (-5060 710);
PAINT ORANGE (-5060 710);
FORCEPROP 2 LASTPIN (-5050 650) $PN F55
J 2
(-5060 660);
DISPLAY 0.617021 (-5060 660);
PAINT ORANGE (-5060 660);
FORCEPROP 2 LASTPIN (-3350 1850) $PN D63
J 0
(-3340 1860);
DISPLAY 0.617021 (-3340 1860);
PAINT ORANGE (-3340 1860);
FORCEPROP 2 LASTPIN (-3350 1800) $PN B63
J 0
(-3340 1810);
DISPLAY 0.617021 (-3340 1810);
PAINT ORANGE (-3340 1810);
FORCEPROP 2 LASTPIN (-3350 1750) $PN C64
J 0
(-3340 1760);
DISPLAY 0.617021 (-3340 1760);
PAINT ORANGE (-3340 1760);
FORCEPROP 2 LASTPIN (-3350 1700) $PN C62
J 0
(-3340 1710);
DISPLAY 0.617021 (-3340 1710);
PAINT ORANGE (-3340 1710);
FORCEPROP 2 LASTPIN (-5050 550) $PN G46
J 2
(-5060 560);
DISPLAY 0.617021 (-5060 560);
PAINT ORANGE (-5060 560);
FORCEPROP 2 LASTPIN (-3350 900) $PN F63
J 0
(-3340 910);
DISPLAY 0.617021 (-3340 910);
PAINT ORANGE (-3340 910);
FORCEPROP 2 LASTPIN (-3350 850) $PN D61
J 0
(-3340 860);
DISPLAY 0.617021 (-3340 860);
PAINT ORANGE (-3340 860);
FORCEPROP 2 LASTPIN (-3350 800) $PN G54
J 0
(-3340 810);
DISPLAY 0.617021 (-3340 810);
PAINT ORANGE (-3340 810);
FORCEPROP 2 LASTPIN (-3350 750) $PN C52
J 0
(-3340 760);
DISPLAY 0.617021 (-3340 760);
PAINT ORANGE (-3340 760);
FORCEPROP 2 LASTPIN (-3350 600) $PN B61
J 0
(-3340 610);
DISPLAY 0.617021 (-3340 610);
PAINT ORANGE (-3340 610);
FORCEPROP 2 LASTPIN (-3350 650) $PN J60
J 0
(-3340 660);
DISPLAY 0.617021 (-3340 660);
PAINT ORANGE (-3340 660);
FORCEPROP 2 LASTPIN (-5050 2950) $PN M77
J 2
(-5060 2960);
DISPLAY 0.617021 (-5060 2960);
PAINT ORANGE (-5060 2960);
FORCEPROP 2 LASTPIN (-5050 2900) $PN P73
J 2
(-5060 2910);
DISPLAY 0.617021 (-5060 2910);
PAINT ORANGE (-5060 2910);
FORCEPROP 1 LAST PACK_TYPE BGA1
J 0
(-5000 5000);
PAINT SKYBLUE (-5000 5000);
DISPLAY INVISIBLE (-5000 5000);
FORCEPROP 2 LAST CDS_LIB chpset_lib
J 0
(-4200 2600);
PAINT ORANGE (-4200 2600);
DISPLAY INVISIBLE (-4200 2600);
FORCEPROP 2 LAST SEC_TYPE BGA1
J 0
(-5000 5000);
DISPLAY 1.021277 (-5000 5000);
PAINT ORANGE (-5000 5000);
DISPLAY INVISIBLE (-5000 5000);
FORCEPROP 2 LAST SEC 3
J 0
(-5000 5000);
DISPLAY 0.680851 (-5000 5000);
PAINT MONO (-5000 5000);
DISPLAY INVISIBLE (-5000 5000);
FORCEPROP 2 LAST CDS_LOCATION U5D1
J 0
(-5000 4950);
DISPLAY 0.617021 (-5000 4950);
PAINT AQUA (-5000 4950);
DISPLAY INVISIBLE (-5000 4950);
FORCEPROP 1 LAST PATH I172
J 0
(-4200 4900);
PAINT GREEN (-4200 4900);
DISPLAY INVISIBLE (-4200 4900);
FORCEPROP 0 LAST ROOM CPU0
J 0
(-5000 5050);
DISPLAY 1.021277 (-5000 5050);
PAINT ORANGE (-5000 5050);
DISPLAY INVISIBLE (-5000 5050);
FORCEADD TAP..6
(-5600 1350);
FORCEPROP 3 LASTPIN (-5550 1350) SIG_NAME M_A_ECC<5>
J 0
(-5540 1360);
DISPLAY 0.659574 (-5540 1360);
PAINT MONO (-5540 1360);
DISPLAY INVISIBLE (-5540 1360);
FORCEPROP 1 LASTPIN (-5550 1350) BN 5
J 0
(-5602 1358);
DISPLAY 0.617021 (-5602 1358);
PAINT PINK (-5602 1358);
FORCEPROP 2 LAST CDS_LIB mstr_standard
J 0
(-5600 1350);
PAINT MONO (-5600 1350);
DISPLAY INVISIBLE (-5600 1350);
FORCEPROP 1 LAST PATH I18
J 0
(-5602 1350);
DISPLAY 0.872340 (-5602 1350);
PAINT GREEN (-5602 1350);
DISPLAY INVISIBLE (-5602 1350);
FORCEPROP 1 LAST BODY_TYPE PLUMBING
J 0
(-5600 1300);
DISPLAY 1.595745 (-5600 1300);
PAINT GREEN (-5600 1300);
DISPLAY INVISIBLE (-5600 1300);
FORCEPROP 1 LAST HDL_TAP TRUE
J 0
(-5275 1225);
DISPLAY 1.595745 (-5275 1225);
PAINT GREEN (-5275 1225);
DISPLAY INVISIBLE (-5275 1225);
FORCEADD TAP..6
(-5600 1400);
FORCEPROP 3 LASTPIN (-5550 1400) SIG_NAME M_A_ECC<6>
J 0
(-5540 1410);
DISPLAY 0.659574 (-5540 1410);
PAINT MONO (-5540 1410);
DISPLAY INVISIBLE (-5540 1410);
FORCEPROP 1 LASTPIN (-5550 1400) BN 6
J 0
(-5602 1408);
DISPLAY 0.617021 (-5602 1408);
PAINT PINK (-5602 1408);
FORCEPROP 2 LAST CDS_LIB mstr_standard
J 0
(-5600 1400);
PAINT MONO (-5600 1400);
DISPLAY INVISIBLE (-5600 1400);
FORCEPROP 1 LAST PATH I19
J 0
(-5602 1400);
DISPLAY 0.872340 (-5602 1400);
PAINT GREEN (-5602 1400);
DISPLAY INVISIBLE (-5602 1400);
FORCEPROP 1 LAST BODY_TYPE PLUMBING
J 0
(-5600 1350);
DISPLAY 1.595745 (-5600 1350);
PAINT GREEN (-5600 1350);
DISPLAY INVISIBLE (-5600 1350);
FORCEPROP 1 LAST HDL_TAP TRUE
J 0
(-5275 1275);
DISPLAY 1.595745 (-5275 1275);
PAINT GREEN (-5275 1275);
DISPLAY INVISIBLE (-5275 1275);
FORCEADD OFFPAGE..5
(-6450 1050);
FORCEPROP 2 LAST $XR1 44 
J 0
(-6764 1050);
DISPLAY 0.638298 (-6764 1050);
PAINT MONO (-6764 1050);
FORCEPROP 2 LAST $XR0 43 
J 0
(-6674 1050);
DISPLAY 0.638298 (-6674 1050);
PAINT MONO (-6674 1050);
FORCEPROP 2 LAST CDS_LIB mstr_standard
J 0
(-6450 1050);
PAINT MONO (-6450 1050);
DISPLAY INVISIBLE (-6450 1050);
FORCEPROP 2 LAST PATH I2
J 0
(-6400 1125);
DISPLAY 1.021277 (-6400 1125);
PAINT ORANGE (-6400 1125);
DISPLAY INVISIBLE (-6400 1125);
FORCEPROP 1 LAST OFFPAGE TRUE
J 0
(-6125 925);
DISPLAY 1.170213 (-6125 925);
PAINT GREEN (-6125 925);
DISPLAY INVISIBLE (-6125 925);
FORCEPROP 1 LAST COMMENT_BODY TRUE
J 0
(-6350 975);
DISPLAY 1.170213 (-6350 975);
PAINT GREEN (-6350 975);
DISPLAY INVISIBLE (-6350 975);
FORCEADD TAP..6
(-5600 1450);
FORCEPROP 3 LASTPIN (-5550 1450) SIG_NAME M_A_ECC<7>
J 0
(-5540 1460);
DISPLAY 0.659574 (-5540 1460);
PAINT MONO (-5540 1460);
DISPLAY INVISIBLE (-5540 1460);
FORCEPROP 1 LASTPIN (-5550 1450) BN 7
J 0
(-5602 1458);
DISPLAY 0.617021 (-5602 1458);
PAINT PINK (-5602 1458);
FORCEPROP 2 LAST CDS_LIB mstr_standard
J 0
(-5600 1450);
PAINT MONO (-5600 1450);
DISPLAY INVISIBLE (-5600 1450);
FORCEPROP 1 LAST PATH I20
J 0
(-5602 1450);
DISPLAY 0.872340 (-5602 1450);
PAINT GREEN (-5602 1450);
DISPLAY INVISIBLE (-5602 1450);
FORCEPROP 1 LAST BODY_TYPE PLUMBING
J 0
(-5600 1400);
DISPLAY 1.595745 (-5600 1400);
PAINT GREEN (-5600 1400);
DISPLAY INVISIBLE (-5600 1400);
FORCEPROP 1 LAST HDL_TAP TRUE
J 0
(-5275 1325);
DISPLAY 1.595745 (-5275 1325);
PAINT GREEN (-5275 1325);
DISPLAY INVISIBLE (-5275 1325);
FORCEADD TAP..6
(-5600 1600);
FORCEPROP 3 LASTPIN (-5550 1600) SIG_NAME M_A_DQ<1>
J 0
(-5540 1610);
DISPLAY 0.659574 (-5540 1610);
PAINT MONO (-5540 1610);
DISPLAY INVISIBLE (-5540 1610);
FORCEPROP 1 LASTPIN (-5550 1600) BN 1
J 0
(-5602 1608);
DISPLAY 0.617021 (-5602 1608);
PAINT PINK (-5602 1608);
FORCEPROP 2 LAST CDS_LIB mstr_standard
J 0
(-5600 1600);
PAINT MONO (-5600 1600);
DISPLAY INVISIBLE (-5600 1600);
FORCEPROP 1 LAST PATH I21
J 0
(-5602 1600);
DISPLAY 0.872340 (-5602 1600);
PAINT GREEN (-5602 1600);
DISPLAY INVISIBLE (-5602 1600);
FORCEPROP 1 LAST BODY_TYPE PLUMBING
J 0
(-5600 1550);
DISPLAY 1.595745 (-5600 1550);
PAINT GREEN (-5600 1550);
DISPLAY INVISIBLE (-5600 1550);
FORCEPROP 1 LAST HDL_TAP TRUE
J 0
(-5275 1475);
DISPLAY 1.595745 (-5275 1475);
PAINT GREEN (-5275 1475);
DISPLAY INVISIBLE (-5275 1475);
FORCEADD TAP..6
(-5600 1550);
FORCEPROP 3 LASTPIN (-5550 1550) SIG_NAME M_A_DQ<0>
J 0
(-5540 1560);
DISPLAY 0.659574 (-5540 1560);
PAINT MONO (-5540 1560);
DISPLAY INVISIBLE (-5540 1560);
FORCEPROP 1 LASTPIN (-5550 1550) BN 0
J 0
(-5602 1558);
DISPLAY 0.617021 (-5602 1558);
PAINT PINK (-5602 1558);
FORCEPROP 2 LAST CDS_LIB mstr_standard
J 0
(-5600 1550);
PAINT MONO (-5600 1550);
DISPLAY INVISIBLE (-5600 1550);
FORCEPROP 1 LAST PATH I22
J 0
(-5602 1550);
DISPLAY 0.872340 (-5602 1550);
PAINT GREEN (-5602 1550);
DISPLAY INVISIBLE (-5602 1550);
FORCEPROP 1 LAST BODY_TYPE PLUMBING
J 0
(-5600 1500);
DISPLAY 1.595745 (-5600 1500);
PAINT GREEN (-5600 1500);
DISPLAY INVISIBLE (-5600 1500);
FORCEPROP 1 LAST HDL_TAP TRUE
J 0
(-5275 1425);
DISPLAY 1.595745 (-5275 1425);
PAINT GREEN (-5275 1425);
DISPLAY INVISIBLE (-5275 1425);
FORCEADD TAP..6
(-5600 1650);
FORCEPROP 3 LASTPIN (-5550 1650) SIG_NAME M_A_DQ<2>
J 0
(-5540 1660);
DISPLAY 0.659574 (-5540 1660);
PAINT MONO (-5540 1660);
DISPLAY INVISIBLE (-5540 1660);
FORCEPROP 1 LASTPIN (-5550 1650) BN 2
J 0
(-5602 1658);
DISPLAY 0.617021 (-5602 1658);
PAINT PINK (-5602 1658);
FORCEPROP 2 LAST CDS_LIB mstr_standard
J 0
(-5600 1650);
PAINT MONO (-5600 1650);
DISPLAY INVISIBLE (-5600 1650);
FORCEPROP 1 LAST PATH I23
J 0
(-5602 1650);
DISPLAY 0.872340 (-5602 1650);
PAINT GREEN (-5602 1650);
DISPLAY INVISIBLE (-5602 1650);
FORCEPROP 1 LAST BODY_TYPE PLUMBING
J 0
(-5600 1600);
DISPLAY 1.595745 (-5600 1600);
PAINT GREEN (-5600 1600);
DISPLAY INVISIBLE (-5600 1600);
FORCEPROP 1 LAST HDL_TAP TRUE
J 0
(-5275 1525);
DISPLAY 1.595745 (-5275 1525);
PAINT GREEN (-5275 1525);
DISPLAY INVISIBLE (-5275 1525);
FORCEADD TAP..6
(-5600 1700);
FORCEPROP 3 LASTPIN (-5550 1700) SIG_NAME M_A_DQ<3>
J 0
(-5540 1710);
DISPLAY 0.659574 (-5540 1710);
PAINT MONO (-5540 1710);
DISPLAY INVISIBLE (-5540 1710);
FORCEPROP 1 LASTPIN (-5550 1700) BN 3
J 0
(-5602 1708);
DISPLAY 0.617021 (-5602 1708);
PAINT PINK (-5602 1708);
FORCEPROP 2 LAST CDS_LIB mstr_standard
J 0
(-5600 1700);
PAINT MONO (-5600 1700);
DISPLAY INVISIBLE (-5600 1700);
FORCEPROP 1 LAST PATH I24
J 0
(-5602 1700);
DISPLAY 0.872340 (-5602 1700);
PAINT GREEN (-5602 1700);
DISPLAY INVISIBLE (-5602 1700);
FORCEPROP 1 LAST BODY_TYPE PLUMBING
J 0
(-5600 1650);
DISPLAY 1.595745 (-5600 1650);
PAINT GREEN (-5600 1650);
DISPLAY INVISIBLE (-5600 1650);
FORCEPROP 1 LAST HDL_TAP TRUE
J 0
(-5275 1575);
DISPLAY 1.595745 (-5275 1575);
PAINT GREEN (-5275 1575);
DISPLAY INVISIBLE (-5275 1575);
FORCEADD TAP..6
(-5600 1750);
FORCEPROP 3 LASTPIN (-5550 1750) SIG_NAME M_A_DQ<4>
J 0
(-5540 1760);
DISPLAY 0.659574 (-5540 1760);
PAINT MONO (-5540 1760);
DISPLAY INVISIBLE (-5540 1760);
FORCEPROP 1 LASTPIN (-5550 1750) BN 4
J 0
(-5602 1758);
DISPLAY 0.617021 (-5602 1758);
PAINT PINK (-5602 1758);
FORCEPROP 2 LAST CDS_LIB mstr_standard
J 0
(-5600 1750);
PAINT MONO (-5600 1750);
DISPLAY INVISIBLE (-5600 1750);
FORCEPROP 1 LAST PATH I25
J 0
(-5602 1750);
DISPLAY 0.872340 (-5602 1750);
PAINT GREEN (-5602 1750);
DISPLAY INVISIBLE (-5602 1750);
FORCEPROP 1 LAST BODY_TYPE PLUMBING
J 0
(-5600 1700);
DISPLAY 1.595745 (-5600 1700);
PAINT GREEN (-5600 1700);
DISPLAY INVISIBLE (-5600 1700);
FORCEPROP 1 LAST HDL_TAP TRUE
J 0
(-5275 1625);
DISPLAY 1.595745 (-5275 1625);
PAINT GREEN (-5275 1625);
DISPLAY INVISIBLE (-5275 1625);
FORCEADD TAP..6
(-5600 1800);
FORCEPROP 3 LASTPIN (-5550 1800) SIG_NAME M_A_DQ<5>
J 0
(-5540 1810);
DISPLAY 0.659574 (-5540 1810);
PAINT MONO (-5540 1810);
DISPLAY INVISIBLE (-5540 1810);
FORCEPROP 1 LASTPIN (-5550 1800) BN 5
J 0
(-5602 1808);
DISPLAY 0.617021 (-5602 1808);
PAINT PINK (-5602 1808);
FORCEPROP 2 LAST CDS_LIB mstr_standard
J 0
(-5600 1800);
PAINT MONO (-5600 1800);
DISPLAY INVISIBLE (-5600 1800);
FORCEPROP 1 LAST PATH I26
J 0
(-5602 1800);
DISPLAY 0.872340 (-5602 1800);
PAINT GREEN (-5602 1800);
DISPLAY INVISIBLE (-5602 1800);
FORCEPROP 1 LAST BODY_TYPE PLUMBING
J 0
(-5600 1750);
DISPLAY 1.595745 (-5600 1750);
PAINT GREEN (-5600 1750);
DISPLAY INVISIBLE (-5600 1750);
FORCEPROP 1 LAST HDL_TAP TRUE
J 0
(-5275 1675);
DISPLAY 1.595745 (-5275 1675);
PAINT GREEN (-5275 1675);
DISPLAY INVISIBLE (-5275 1675);
FORCEADD TAP..6
(-5600 1850);
FORCEPROP 3 LASTPIN (-5550 1850) SIG_NAME M_A_DQ<6>
J 0
(-5540 1860);
DISPLAY 0.659574 (-5540 1860);
PAINT MONO (-5540 1860);
DISPLAY INVISIBLE (-5540 1860);
FORCEPROP 1 LASTPIN (-5550 1850) BN 6
J 0
(-5602 1858);
DISPLAY 0.617021 (-5602 1858);
PAINT PINK (-5602 1858);
FORCEPROP 2 LAST CDS_LIB mstr_standard
J 0
(-5600 1850);
PAINT MONO (-5600 1850);
DISPLAY INVISIBLE (-5600 1850);
FORCEPROP 1 LAST PATH I27
J 0
(-5602 1850);
DISPLAY 0.872340 (-5602 1850);
PAINT GREEN (-5602 1850);
DISPLAY INVISIBLE (-5602 1850);
FORCEPROP 1 LAST BODY_TYPE PLUMBING
J 0
(-5600 1800);
DISPLAY 1.595745 (-5600 1800);
PAINT GREEN (-5600 1800);
DISPLAY INVISIBLE (-5600 1800);
FORCEPROP 1 LAST HDL_TAP TRUE
J 0
(-5275 1725);
DISPLAY 1.595745 (-5275 1725);
PAINT GREEN (-5275 1725);
DISPLAY INVISIBLE (-5275 1725);
FORCEADD TAP..6
(-5600 1950);
FORCEPROP 3 LASTPIN (-5550 1950) SIG_NAME M_A_DQ<8>
J 0
(-5540 1960);
DISPLAY 0.659574 (-5540 1960);
PAINT MONO (-5540 1960);
DISPLAY INVISIBLE (-5540 1960);
FORCEPROP 1 LASTPIN (-5550 1950) BN 8
J 0
(-5602 1958);
DISPLAY 0.617021 (-5602 1958);
PAINT PINK (-5602 1958);
FORCEPROP 2 LAST CDS_LIB mstr_standard
J 0
(-5600 1950);
PAINT MONO (-5600 1950);
DISPLAY INVISIBLE (-5600 1950);
FORCEPROP 1 LAST PATH I28
J 0
(-5602 1950);
DISPLAY 0.872340 (-5602 1950);
PAINT GREEN (-5602 1950);
DISPLAY INVISIBLE (-5602 1950);
FORCEPROP 1 LAST BODY_TYPE PLUMBING
J 0
(-5600 1900);
DISPLAY 1.595745 (-5600 1900);
PAINT GREEN (-5600 1900);
DISPLAY INVISIBLE (-5600 1900);
FORCEPROP 1 LAST HDL_TAP TRUE
J 0
(-5275 1825);
DISPLAY 1.595745 (-5275 1825);
PAINT GREEN (-5275 1825);
DISPLAY INVISIBLE (-5275 1825);
FORCEADD TAP..6
(-5600 1900);
FORCEPROP 3 LASTPIN (-5550 1900) SIG_NAME M_A_DQ<7>
J 0
(-5540 1910);
DISPLAY 0.659574 (-5540 1910);
PAINT MONO (-5540 1910);
DISPLAY INVISIBLE (-5540 1910);
FORCEPROP 1 LASTPIN (-5550 1900) BN 7
J 0
(-5602 1908);
DISPLAY 0.617021 (-5602 1908);
PAINT PINK (-5602 1908);
FORCEPROP 2 LAST CDS_LIB mstr_standard
J 0
(-5600 1900);
PAINT MONO (-5600 1900);
DISPLAY INVISIBLE (-5600 1900);
FORCEPROP 1 LAST PATH I29
J 0
(-5602 1900);
DISPLAY 0.872340 (-5602 1900);
PAINT GREEN (-5602 1900);
DISPLAY INVISIBLE (-5602 1900);
FORCEPROP 1 LAST BODY_TYPE PLUMBING
J 0
(-5600 1850);
DISPLAY 1.595745 (-5600 1850);
PAINT GREEN (-5600 1850);
DISPLAY INVISIBLE (-5600 1850);
FORCEPROP 1 LAST HDL_TAP TRUE
J 0
(-5275 1775);
DISPLAY 1.595745 (-5275 1775);
PAINT GREEN (-5275 1775);
DISPLAY INVISIBLE (-5275 1775);
FORCEADD OFFPAGE..5
(-6450 850);
FORCEPROP 2 LAST $XR1 44 
J 0
(-6764 850);
DISPLAY 0.638298 (-6764 850);
PAINT MONO (-6764 850);
FORCEPROP 2 LAST $XR0 43 
J 0
(-6674 850);
DISPLAY 0.638298 (-6674 850);
PAINT MONO (-6674 850);
FORCEPROP 2 LAST CDS_LIB mstr_standard
J 0
(-6450 850);
PAINT MONO (-6450 850);
DISPLAY INVISIBLE (-6450 850);
FORCEPROP 2 LAST PATH I3
J 0
(-6400 925);
DISPLAY 1.021277 (-6400 925);
PAINT ORANGE (-6400 925);
DISPLAY INVISIBLE (-6400 925);
FORCEPROP 1 LAST OFFPAGE TRUE
J 0
(-6125 725);
DISPLAY 1.170213 (-6125 725);
PAINT GREEN (-6125 725);
DISPLAY INVISIBLE (-6125 725);
FORCEPROP 1 LAST COMMENT_BODY TRUE
J 0
(-6350 775);
DISPLAY 1.170213 (-6350 775);
PAINT GREEN (-6350 775);
DISPLAY INVISIBLE (-6350 775);
FORCEADD TAP..6
(-5600 2000);
FORCEPROP 3 LASTPIN (-5550 2000) SIG_NAME M_A_DQ<9>
J 0
(-5540 2010);
DISPLAY 0.659574 (-5540 2010);
PAINT MONO (-5540 2010);
DISPLAY INVISIBLE (-5540 2010);
FORCEPROP 1 LASTPIN (-5550 2000) BN 9
J 0
(-5602 2008);
DISPLAY 0.617021 (-5602 2008);
PAINT PINK (-5602 2008);
FORCEPROP 2 LAST CDS_LIB mstr_standard
J 0
(-5600 2000);
PAINT MONO (-5600 2000);
DISPLAY INVISIBLE (-5600 2000);
FORCEPROP 1 LAST PATH I31
J 0
(-5602 2000);
DISPLAY 0.872340 (-5602 2000);
PAINT GREEN (-5602 2000);
DISPLAY INVISIBLE (-5602 2000);
FORCEPROP 1 LAST BODY_TYPE PLUMBING
J 0
(-5600 1950);
DISPLAY 1.595745 (-5600 1950);
PAINT GREEN (-5600 1950);
DISPLAY INVISIBLE (-5600 1950);
FORCEPROP 1 LAST HDL_TAP TRUE
J 0
(-5275 1875);
DISPLAY 1.595745 (-5275 1875);
PAINT GREEN (-5275 1875);
DISPLAY INVISIBLE (-5275 1875);
FORCEADD TAP..6
(-5600 2050);
FORCEPROP 3 LASTPIN (-5550 2050) SIG_NAME M_A_DQ<10>
J 0
(-5540 2060);
DISPLAY 0.659574 (-5540 2060);
PAINT MONO (-5540 2060);
DISPLAY INVISIBLE (-5540 2060);
FORCEPROP 1 LASTPIN (-5550 2050) BN 10
J 0
(-5602 2058);
DISPLAY 0.617021 (-5602 2058);
PAINT PINK (-5602 2058);
FORCEPROP 2 LAST CDS_LIB mstr_standard
J 0
(-5600 2050);
PAINT MONO (-5600 2050);
DISPLAY INVISIBLE (-5600 2050);
FORCEPROP 1 LAST PATH I32
J 0
(-5602 2050);
DISPLAY 0.872340 (-5602 2050);
PAINT GREEN (-5602 2050);
DISPLAY INVISIBLE (-5602 2050);
FORCEPROP 1 LAST BODY_TYPE PLUMBING
J 0
(-5600 2000);
DISPLAY 1.595745 (-5600 2000);
PAINT GREEN (-5600 2000);
DISPLAY INVISIBLE (-5600 2000);
FORCEPROP 1 LAST HDL_TAP TRUE
J 0
(-5275 1925);
DISPLAY 1.595745 (-5275 1925);
PAINT GREEN (-5275 1925);
DISPLAY INVISIBLE (-5275 1925);
FORCEADD TAP..6
(-5600 2100);
FORCEPROP 3 LASTPIN (-5550 2100) SIG_NAME M_A_DQ<11>
J 0
(-5540 2110);
DISPLAY 0.659574 (-5540 2110);
PAINT MONO (-5540 2110);
DISPLAY INVISIBLE (-5540 2110);
FORCEPROP 1 LASTPIN (-5550 2100) BN 11
J 0
(-5602 2108);
DISPLAY 0.617021 (-5602 2108);
PAINT PINK (-5602 2108);
FORCEPROP 2 LAST CDS_LIB mstr_standard
J 0
(-5600 2100);
PAINT MONO (-5600 2100);
DISPLAY INVISIBLE (-5600 2100);
FORCEPROP 1 LAST PATH I33
J 0
(-5602 2100);
DISPLAY 0.872340 (-5602 2100);
PAINT GREEN (-5602 2100);
DISPLAY INVISIBLE (-5602 2100);
FORCEPROP 1 LAST BODY_TYPE PLUMBING
J 0
(-5600 2050);
DISPLAY 1.595745 (-5600 2050);
PAINT GREEN (-5600 2050);
DISPLAY INVISIBLE (-5600 2050);
FORCEPROP 1 LAST HDL_TAP TRUE
J 0
(-5275 1975);
DISPLAY 1.595745 (-5275 1975);
PAINT GREEN (-5275 1975);
DISPLAY INVISIBLE (-5275 1975);
FORCEADD TAP..6
(-5600 2150);
FORCEPROP 3 LASTPIN (-5550 2150) SIG_NAME M_A_DQ<12>
J 0
(-5540 2160);
DISPLAY 0.659574 (-5540 2160);
PAINT MONO (-5540 2160);
DISPLAY INVISIBLE (-5540 2160);
FORCEPROP 1 LASTPIN (-5550 2150) BN 12
J 0
(-5602 2158);
DISPLAY 0.617021 (-5602 2158);
PAINT PINK (-5602 2158);
FORCEPROP 2 LAST CDS_LIB mstr_standard
J 0
(-5600 2150);
PAINT MONO (-5600 2150);
DISPLAY INVISIBLE (-5600 2150);
FORCEPROP 1 LAST PATH I34
J 0
(-5602 2150);
DISPLAY 0.872340 (-5602 2150);
PAINT GREEN (-5602 2150);
DISPLAY INVISIBLE (-5602 2150);
FORCEPROP 1 LAST BODY_TYPE PLUMBING
J 0
(-5600 2100);
DISPLAY 1.595745 (-5600 2100);
PAINT GREEN (-5600 2100);
DISPLAY INVISIBLE (-5600 2100);
FORCEPROP 1 LAST HDL_TAP TRUE
J 0
(-5275 2025);
DISPLAY 1.595745 (-5275 2025);
PAINT GREEN (-5275 2025);
DISPLAY INVISIBLE (-5275 2025);
FORCEADD TAP..6
(-5600 2200);
FORCEPROP 3 LASTPIN (-5550 2200) SIG_NAME M_A_DQ<13>
J 0
(-5540 2210);
DISPLAY 0.659574 (-5540 2210);
PAINT MONO (-5540 2210);
DISPLAY INVISIBLE (-5540 2210);
FORCEPROP 1 LASTPIN (-5550 2200) BN 13
J 0
(-5602 2208);
DISPLAY 0.617021 (-5602 2208);
PAINT PINK (-5602 2208);
FORCEPROP 2 LAST CDS_LIB mstr_standard
J 0
(-5600 2200);
PAINT MONO (-5600 2200);
DISPLAY INVISIBLE (-5600 2200);
FORCEPROP 1 LAST PATH I35
J 0
(-5602 2200);
DISPLAY 0.872340 (-5602 2200);
PAINT GREEN (-5602 2200);
DISPLAY INVISIBLE (-5602 2200);
FORCEPROP 1 LAST BODY_TYPE PLUMBING
J 0
(-5600 2150);
DISPLAY 1.595745 (-5600 2150);
PAINT GREEN (-5600 2150);
DISPLAY INVISIBLE (-5600 2150);
FORCEPROP 1 LAST HDL_TAP TRUE
J 0
(-5275 2075);
DISPLAY 1.595745 (-5275 2075);
PAINT GREEN (-5275 2075);
DISPLAY INVISIBLE (-5275 2075);
FORCEADD TAP..6
(-5600 2250);
FORCEPROP 3 LASTPIN (-5550 2250) SIG_NAME M_A_DQ<14>
J 0
(-5540 2260);
DISPLAY 0.659574 (-5540 2260);
PAINT MONO (-5540 2260);
DISPLAY INVISIBLE (-5540 2260);
FORCEPROP 1 LASTPIN (-5550 2250) BN 14
J 0
(-5602 2258);
DISPLAY 0.617021 (-5602 2258);
PAINT PINK (-5602 2258);
FORCEPROP 2 LAST CDS_LIB mstr_standard
J 0
(-5600 2250);
PAINT MONO (-5600 2250);
DISPLAY INVISIBLE (-5600 2250);
FORCEPROP 1 LAST PATH I36
J 0
(-5602 2250);
DISPLAY 0.872340 (-5602 2250);
PAINT GREEN (-5602 2250);
DISPLAY INVISIBLE (-5602 2250);
FORCEPROP 1 LAST BODY_TYPE PLUMBING
J 0
(-5600 2200);
DISPLAY 1.595745 (-5600 2200);
PAINT GREEN (-5600 2200);
DISPLAY INVISIBLE (-5600 2200);
FORCEPROP 1 LAST HDL_TAP TRUE
J 0
(-5275 2125);
DISPLAY 1.595745 (-5275 2125);
PAINT GREEN (-5275 2125);
DISPLAY INVISIBLE (-5275 2125);
FORCEADD TAP..6
(-5600 2300);
FORCEPROP 3 LASTPIN (-5550 2300) SIG_NAME M_A_DQ<15>
J 0
(-5540 2310);
DISPLAY 0.659574 (-5540 2310);
PAINT MONO (-5540 2310);
DISPLAY INVISIBLE (-5540 2310);
FORCEPROP 1 LASTPIN (-5550 2300) BN 15
J 0
(-5602 2308);
DISPLAY 0.617021 (-5602 2308);
PAINT PINK (-5602 2308);
FORCEPROP 2 LAST CDS_LIB mstr_standard
J 0
(-5600 2300);
PAINT MONO (-5600 2300);
DISPLAY INVISIBLE (-5600 2300);
FORCEPROP 1 LAST PATH I37
J 0
(-5602 2300);
DISPLAY 0.872340 (-5602 2300);
PAINT GREEN (-5602 2300);
DISPLAY INVISIBLE (-5602 2300);
FORCEPROP 1 LAST BODY_TYPE PLUMBING
J 0
(-5600 2250);
DISPLAY 1.595745 (-5600 2250);
PAINT GREEN (-5600 2250);
DISPLAY INVISIBLE (-5600 2250);
FORCEPROP 1 LAST HDL_TAP TRUE
J 0
(-5275 2175);
DISPLAY 1.595745 (-5275 2175);
PAINT GREEN (-5275 2175);
DISPLAY INVISIBLE (-5275 2175);
FORCEADD TAP..6
(-5600 2350);
FORCEPROP 3 LASTPIN (-5550 2350) SIG_NAME M_A_DQ<16>
J 0
(-5540 2360);
DISPLAY 0.659574 (-5540 2360);
PAINT MONO (-5540 2360);
DISPLAY INVISIBLE (-5540 2360);
FORCEPROP 1 LASTPIN (-5550 2350) BN 16
J 0
(-5602 2358);
DISPLAY 0.617021 (-5602 2358);
PAINT PINK (-5602 2358);
FORCEPROP 2 LAST CDS_LIB mstr_standard
J 0
(-5600 2350);
PAINT MONO (-5600 2350);
DISPLAY INVISIBLE (-5600 2350);
FORCEPROP 1 LAST PATH I38
J 0
(-5602 2350);
DISPLAY 0.872340 (-5602 2350);
PAINT GREEN (-5602 2350);
DISPLAY INVISIBLE (-5602 2350);
FORCEPROP 1 LAST BODY_TYPE PLUMBING
J 0
(-5600 2300);
DISPLAY 1.595745 (-5600 2300);
PAINT GREEN (-5600 2300);
DISPLAY INVISIBLE (-5600 2300);
FORCEPROP 1 LAST HDL_TAP TRUE
J 0
(-5275 2225);
DISPLAY 1.595745 (-5275 2225);
PAINT GREEN (-5275 2225);
DISPLAY INVISIBLE (-5275 2225);
FORCEADD TAP..6
(-5600 2400);
FORCEPROP 3 LASTPIN (-5550 2400) SIG_NAME M_A_DQ<17>
J 0
(-5540 2410);
DISPLAY 0.659574 (-5540 2410);
PAINT MONO (-5540 2410);
DISPLAY INVISIBLE (-5540 2410);
FORCEPROP 1 LASTPIN (-5550 2400) BN 17
J 0
(-5602 2408);
DISPLAY 0.617021 (-5602 2408);
PAINT PINK (-5602 2408);
FORCEPROP 2 LAST CDS_LIB mstr_standard
J 0
(-5600 2400);
PAINT MONO (-5600 2400);
DISPLAY INVISIBLE (-5600 2400);
FORCEPROP 1 LAST PATH I39
J 0
(-5602 2400);
DISPLAY 0.872340 (-5602 2400);
PAINT GREEN (-5602 2400);
DISPLAY INVISIBLE (-5602 2400);
FORCEPROP 1 LAST BODY_TYPE PLUMBING
J 0
(-5600 2350);
DISPLAY 1.595745 (-5600 2350);
PAINT GREEN (-5600 2350);
DISPLAY INVISIBLE (-5600 2350);
FORCEPROP 1 LAST HDL_TAP TRUE
J 0
(-5275 2275);
DISPLAY 1.595745 (-5275 2275);
PAINT GREEN (-5275 2275);
DISPLAY INVISIBLE (-5275 2275);
FORCEADD OFFPAGE..5
(-6450 550);
FORCEPROP 2 LAST $XR1 44 
J 0
(-6764 550);
DISPLAY 0.638298 (-6764 550);
PAINT MONO (-6764 550);
FORCEPROP 2 LAST $XR0 43 
J 0
(-6674 550);
DISPLAY 0.638298 (-6674 550);
PAINT MONO (-6674 550);
FORCEPROP 2 LAST CDS_LIB mstr_standard
J 0
(-6450 550);
PAINT MONO (-6450 550);
DISPLAY INVISIBLE (-6450 550);
FORCEPROP 2 LAST PATH I4
J 0
(-6400 625);
DISPLAY 1.021277 (-6400 625);
PAINT ORANGE (-6400 625);
DISPLAY INVISIBLE (-6400 625);
FORCEPROP 1 LAST OFFPAGE TRUE
J 0
(-6125 425);
DISPLAY 1.170213 (-6125 425);
PAINT GREEN (-6125 425);
DISPLAY INVISIBLE (-6125 425);
FORCEPROP 1 LAST COMMENT_BODY TRUE
J 0
(-6350 475);
DISPLAY 1.170213 (-6350 475);
PAINT GREEN (-6350 475);
DISPLAY INVISIBLE (-6350 475);
FORCEADD TAP..6
(-5600 2450);
FORCEPROP 3 LASTPIN (-5550 2450) SIG_NAME M_A_DQ<18>
J 0
(-5540 2460);
DISPLAY 0.659574 (-5540 2460);
PAINT MONO (-5540 2460);
DISPLAY INVISIBLE (-5540 2460);
FORCEPROP 1 LASTPIN (-5550 2450) BN 18
J 0
(-5602 2458);
DISPLAY 0.617021 (-5602 2458);
PAINT PINK (-5602 2458);
FORCEPROP 2 LAST CDS_LIB mstr_standard
J 0
(-5600 2450);
PAINT MONO (-5600 2450);
DISPLAY INVISIBLE (-5600 2450);
FORCEPROP 1 LAST PATH I40
J 0
(-5602 2450);
DISPLAY 0.872340 (-5602 2450);
PAINT GREEN (-5602 2450);
DISPLAY INVISIBLE (-5602 2450);
FORCEPROP 1 LAST BODY_TYPE PLUMBING
J 0
(-5600 2400);
DISPLAY 1.595745 (-5600 2400);
PAINT GREEN (-5600 2400);
DISPLAY INVISIBLE (-5600 2400);
FORCEPROP 1 LAST HDL_TAP TRUE
J 0
(-5275 2325);
DISPLAY 1.595745 (-5275 2325);
PAINT GREEN (-5275 2325);
DISPLAY INVISIBLE (-5275 2325);
FORCEADD TAP..6
(-5600 2500);
FORCEPROP 3 LASTPIN (-5550 2500) SIG_NAME M_A_DQ<19>
J 0
(-5540 2510);
DISPLAY 0.659574 (-5540 2510);
PAINT MONO (-5540 2510);
DISPLAY INVISIBLE (-5540 2510);
FORCEPROP 1 LASTPIN (-5550 2500) BN 19
J 0
(-5602 2508);
DISPLAY 0.617021 (-5602 2508);
PAINT PINK (-5602 2508);
FORCEPROP 2 LAST CDS_LIB mstr_standard
J 0
(-5600 2500);
PAINT MONO (-5600 2500);
DISPLAY INVISIBLE (-5600 2500);
FORCEPROP 1 LAST PATH I41
J 0
(-5602 2500);
DISPLAY 0.872340 (-5602 2500);
PAINT GREEN (-5602 2500);
DISPLAY INVISIBLE (-5602 2500);
FORCEPROP 1 LAST BODY_TYPE PLUMBING
J 0
(-5600 2450);
DISPLAY 1.595745 (-5600 2450);
PAINT GREEN (-5600 2450);
DISPLAY INVISIBLE (-5600 2450);
FORCEPROP 1 LAST HDL_TAP TRUE
J 0
(-5275 2375);
DISPLAY 1.595745 (-5275 2375);
PAINT GREEN (-5275 2375);
DISPLAY INVISIBLE (-5275 2375);
FORCEADD TAP..6
(-5600 2550);
FORCEPROP 3 LASTPIN (-5550 2550) SIG_NAME M_A_DQ<20>
J 0
(-5540 2560);
DISPLAY 0.659574 (-5540 2560);
PAINT MONO (-5540 2560);
DISPLAY INVISIBLE (-5540 2560);
FORCEPROP 1 LASTPIN (-5550 2550) BN 20
J 0
(-5602 2558);
DISPLAY 0.617021 (-5602 2558);
PAINT PINK (-5602 2558);
FORCEPROP 2 LAST CDS_LIB mstr_standard
J 0
(-5600 2550);
PAINT MONO (-5600 2550);
DISPLAY INVISIBLE (-5600 2550);
FORCEPROP 1 LAST PATH I42
J 0
(-5602 2550);
DISPLAY 0.872340 (-5602 2550);
PAINT GREEN (-5602 2550);
DISPLAY INVISIBLE (-5602 2550);
FORCEPROP 1 LAST BODY_TYPE PLUMBING
J 0
(-5600 2500);
DISPLAY 1.595745 (-5600 2500);
PAINT GREEN (-5600 2500);
DISPLAY INVISIBLE (-5600 2500);
FORCEPROP 1 LAST HDL_TAP TRUE
J 0
(-5275 2425);
DISPLAY 1.595745 (-5275 2425);
PAINT GREEN (-5275 2425);
DISPLAY INVISIBLE (-5275 2425);
FORCEADD TAP..6
(-5600 2600);
FORCEPROP 3 LASTPIN (-5550 2600) SIG_NAME M_A_DQ<21>
J 0
(-5540 2610);
DISPLAY 0.659574 (-5540 2610);
PAINT MONO (-5540 2610);
DISPLAY INVISIBLE (-5540 2610);
FORCEPROP 1 LASTPIN (-5550 2600) BN 21
J 0
(-5602 2608);
DISPLAY 0.617021 (-5602 2608);
PAINT PINK (-5602 2608);
FORCEPROP 2 LAST CDS_LIB mstr_standard
J 0
(-5600 2600);
PAINT MONO (-5600 2600);
DISPLAY INVISIBLE (-5600 2600);
FORCEPROP 1 LAST PATH I43
J 0
(-5602 2600);
DISPLAY 0.872340 (-5602 2600);
PAINT GREEN (-5602 2600);
DISPLAY INVISIBLE (-5602 2600);
FORCEPROP 1 LAST BODY_TYPE PLUMBING
J 0
(-5600 2550);
DISPLAY 1.595745 (-5600 2550);
PAINT GREEN (-5600 2550);
DISPLAY INVISIBLE (-5600 2550);
FORCEPROP 1 LAST HDL_TAP TRUE
J 0
(-5275 2475);
DISPLAY 1.595745 (-5275 2475);
PAINT GREEN (-5275 2475);
DISPLAY INVISIBLE (-5275 2475);
FORCEADD TAP..6
(-5600 2650);
FORCEPROP 3 LASTPIN (-5550 2650) SIG_NAME M_A_DQ<22>
J 0
(-5540 2660);
DISPLAY 0.659574 (-5540 2660);
PAINT MONO (-5540 2660);
DISPLAY INVISIBLE (-5540 2660);
FORCEPROP 1 LASTPIN (-5550 2650) BN 22
J 0
(-5602 2658);
DISPLAY 0.617021 (-5602 2658);
PAINT PINK (-5602 2658);
FORCEPROP 2 LAST CDS_LIB mstr_standard
J 0
(-5600 2650);
PAINT MONO (-5600 2650);
DISPLAY INVISIBLE (-5600 2650);
FORCEPROP 1 LAST PATH I44
J 0
(-5602 2650);
DISPLAY 0.872340 (-5602 2650);
PAINT GREEN (-5602 2650);
DISPLAY INVISIBLE (-5602 2650);
FORCEPROP 1 LAST BODY_TYPE PLUMBING
J 0
(-5600 2600);
DISPLAY 1.595745 (-5600 2600);
PAINT GREEN (-5600 2600);
DISPLAY INVISIBLE (-5600 2600);
FORCEPROP 1 LAST HDL_TAP TRUE
J 0
(-5275 2525);
DISPLAY 1.595745 (-5275 2525);
PAINT GREEN (-5275 2525);
DISPLAY INVISIBLE (-5275 2525);
FORCEADD TAP..6
(-5600 2700);
FORCEPROP 3 LASTPIN (-5550 2700) SIG_NAME M_A_DQ<23>
J 0
(-5540 2710);
DISPLAY 0.659574 (-5540 2710);
PAINT MONO (-5540 2710);
DISPLAY INVISIBLE (-5540 2710);
FORCEPROP 1 LASTPIN (-5550 2700) BN 23
J 0
(-5602 2708);
DISPLAY 0.617021 (-5602 2708);
PAINT PINK (-5602 2708);
FORCEPROP 2 LAST CDS_LIB mstr_standard
J 0
(-5600 2700);
PAINT MONO (-5600 2700);
DISPLAY INVISIBLE (-5600 2700);
FORCEPROP 1 LAST PATH I45
J 0
(-5602 2700);
DISPLAY 0.872340 (-5602 2700);
PAINT GREEN (-5602 2700);
DISPLAY INVISIBLE (-5602 2700);
FORCEPROP 1 LAST BODY_TYPE PLUMBING
J 0
(-5600 2650);
DISPLAY 1.595745 (-5600 2650);
PAINT GREEN (-5600 2650);
DISPLAY INVISIBLE (-5600 2650);
FORCEPROP 1 LAST HDL_TAP TRUE
J 0
(-5275 2575);
DISPLAY 1.595745 (-5275 2575);
PAINT GREEN (-5275 2575);
DISPLAY INVISIBLE (-5275 2575);
FORCEADD TAP..6
(-5600 2750);
FORCEPROP 3 LASTPIN (-5550 2750) SIG_NAME M_A_DQ<24>
J 0
(-5540 2760);
DISPLAY 0.659574 (-5540 2760);
PAINT MONO (-5540 2760);
DISPLAY INVISIBLE (-5540 2760);
FORCEPROP 1 LASTPIN (-5550 2750) BN 24
J 0
(-5602 2758);
DISPLAY 0.617021 (-5602 2758);
PAINT PINK (-5602 2758);
FORCEPROP 2 LAST CDS_LIB mstr_standard
J 0
(-5600 2750);
PAINT MONO (-5600 2750);
DISPLAY INVISIBLE (-5600 2750);
FORCEPROP 1 LAST PATH I46
J 0
(-5602 2750);
DISPLAY 0.872340 (-5602 2750);
PAINT GREEN (-5602 2750);
DISPLAY INVISIBLE (-5602 2750);
FORCEPROP 1 LAST BODY_TYPE PLUMBING
J 0
(-5600 2700);
DISPLAY 1.595745 (-5600 2700);
PAINT GREEN (-5600 2700);
DISPLAY INVISIBLE (-5600 2700);
FORCEPROP 1 LAST HDL_TAP TRUE
J 0
(-5275 2625);
DISPLAY 1.595745 (-5275 2625);
PAINT GREEN (-5275 2625);
DISPLAY INVISIBLE (-5275 2625);
FORCEADD TAP..6
(-5600 2850);
FORCEPROP 3 LASTPIN (-5550 2850) SIG_NAME M_A_DQ<26>
J 0
(-5540 2860);
DISPLAY 0.659574 (-5540 2860);
PAINT MONO (-5540 2860);
DISPLAY INVISIBLE (-5540 2860);
FORCEPROP 1 LASTPIN (-5550 2850) BN 26
J 0
(-5602 2858);
DISPLAY 0.617021 (-5602 2858);
PAINT PINK (-5602 2858);
FORCEPROP 2 LAST CDS_LIB mstr_standard
J 0
(-5600 2850);
PAINT MONO (-5600 2850);
DISPLAY INVISIBLE (-5600 2850);
FORCEPROP 1 LAST PATH I47
J 0
(-5602 2850);
DISPLAY 0.872340 (-5602 2850);
PAINT GREEN (-5602 2850);
DISPLAY INVISIBLE (-5602 2850);
FORCEPROP 1 LAST BODY_TYPE PLUMBING
J 0
(-5600 2800);
DISPLAY 1.595745 (-5600 2800);
PAINT GREEN (-5600 2800);
DISPLAY INVISIBLE (-5600 2800);
FORCEPROP 1 LAST HDL_TAP TRUE
J 0
(-5275 2725);
DISPLAY 1.595745 (-5275 2725);
PAINT GREEN (-5275 2725);
DISPLAY INVISIBLE (-5275 2725);
FORCEADD TAP..6
(-5600 2800);
FORCEPROP 3 LASTPIN (-5550 2800) SIG_NAME M_A_DQ<25>
J 0
(-5540 2810);
DISPLAY 0.659574 (-5540 2810);
PAINT MONO (-5540 2810);
DISPLAY INVISIBLE (-5540 2810);
FORCEPROP 1 LASTPIN (-5550 2800) BN 25
J 0
(-5602 2808);
DISPLAY 0.617021 (-5602 2808);
PAINT PINK (-5602 2808);
FORCEPROP 2 LAST CDS_LIB mstr_standard
J 0
(-5600 2800);
PAINT MONO (-5600 2800);
DISPLAY INVISIBLE (-5600 2800);
FORCEPROP 1 LAST PATH I48
J 0
(-5602 2800);
DISPLAY 0.872340 (-5602 2800);
PAINT GREEN (-5602 2800);
DISPLAY INVISIBLE (-5602 2800);
FORCEPROP 1 LAST BODY_TYPE PLUMBING
J 0
(-5600 2750);
DISPLAY 1.595745 (-5600 2750);
PAINT GREEN (-5600 2750);
DISPLAY INVISIBLE (-5600 2750);
FORCEPROP 1 LAST HDL_TAP TRUE
J 0
(-5275 2675);
DISPLAY 1.595745 (-5275 2675);
PAINT GREEN (-5275 2675);
DISPLAY INVISIBLE (-5275 2675);
FORCEADD TAP..6
(-5600 2900);
FORCEPROP 3 LASTPIN (-5550 2900) SIG_NAME M_A_DQ<27>
J 0
(-5540 2910);
DISPLAY 0.659574 (-5540 2910);
PAINT MONO (-5540 2910);
DISPLAY INVISIBLE (-5540 2910);
FORCEPROP 1 LASTPIN (-5550 2900) BN 27
J 0
(-5602 2908);
DISPLAY 0.617021 (-5602 2908);
PAINT PINK (-5602 2908);
FORCEPROP 2 LAST CDS_LIB mstr_standard
J 0
(-5600 2900);
PAINT MONO (-5600 2900);
DISPLAY INVISIBLE (-5600 2900);
FORCEPROP 1 LAST PATH I49
J 0
(-5602 2900);
DISPLAY 0.872340 (-5602 2900);
PAINT GREEN (-5602 2900);
DISPLAY INVISIBLE (-5602 2900);
FORCEPROP 1 LAST BODY_TYPE PLUMBING
J 0
(-5600 2850);
DISPLAY 1.595745 (-5600 2850);
PAINT GREEN (-5600 2850);
DISPLAY INVISIBLE (-5600 2850);
FORCEPROP 1 LAST HDL_TAP TRUE
J 0
(-5275 2775);
DISPLAY 1.595745 (-5275 2775);
PAINT GREEN (-5275 2775);
DISPLAY INVISIBLE (-5275 2775);
FORCEADD TAP..6
(-5600 650);
FORCEPROP 3 LASTPIN (-5550 650) SIG_NAME M_A_CLK_DN<0>
J 0
(-5540 660);
DISPLAY 0.659574 (-5540 660);
PAINT MONO (-5540 660);
DISPLAY INVISIBLE (-5540 660);
FORCEPROP 1 LASTPIN (-5550 650) BN 0
J 0
(-5602 658);
DISPLAY 0.617021 (-5602 658);
PAINT PINK (-5602 658);
FORCEPROP 2 LAST CDS_LIB mstr_standard
J 0
(-5600 650);
PAINT MONO (-5600 650);
DISPLAY INVISIBLE (-5600 650);
FORCEPROP 1 LAST PATH I5
J 0
(-5602 650);
DISPLAY 0.872340 (-5602 650);
PAINT GREEN (-5602 650);
DISPLAY INVISIBLE (-5602 650);
FORCEPROP 1 LAST BODY_TYPE PLUMBING
J 0
(-5600 600);
DISPLAY 1.595745 (-5600 600);
PAINT GREEN (-5600 600);
DISPLAY INVISIBLE (-5600 600);
FORCEPROP 1 LAST HDL_TAP TRUE
J 0
(-5275 525);
DISPLAY 1.595745 (-5275 525);
PAINT GREEN (-5275 525);
DISPLAY INVISIBLE (-5275 525);
FORCEADD TAP..6
(-5600 2950);
FORCEPROP 3 LASTPIN (-5550 2950) SIG_NAME M_A_DQ<28>
J 0
(-5540 2960);
DISPLAY 0.659574 (-5540 2960);
PAINT MONO (-5540 2960);
DISPLAY INVISIBLE (-5540 2960);
FORCEPROP 1 LASTPIN (-5550 2950) BN 28
J 0
(-5602 2958);
DISPLAY 0.617021 (-5602 2958);
PAINT PINK (-5602 2958);
FORCEPROP 2 LAST CDS_LIB mstr_standard
J 0
(-5600 2950);
PAINT MONO (-5600 2950);
DISPLAY INVISIBLE (-5600 2950);
FORCEPROP 1 LAST PATH I50
J 0
(-5602 2950);
DISPLAY 0.872340 (-5602 2950);
PAINT GREEN (-5602 2950);
DISPLAY INVISIBLE (-5602 2950);
FORCEPROP 1 LAST BODY_TYPE PLUMBING
J 0
(-5600 2900);
DISPLAY 1.595745 (-5600 2900);
PAINT GREEN (-5600 2900);
DISPLAY INVISIBLE (-5600 2900);
FORCEPROP 1 LAST HDL_TAP TRUE
J 0
(-5275 2825);
DISPLAY 1.595745 (-5275 2825);
PAINT GREEN (-5275 2825);
DISPLAY INVISIBLE (-5275 2825);
FORCEADD TAP..6
(-5600 3000);
FORCEPROP 3 LASTPIN (-5550 3000) SIG_NAME M_A_DQ<29>
J 0
(-5540 3010);
DISPLAY 0.659574 (-5540 3010);
PAINT MONO (-5540 3010);
DISPLAY INVISIBLE (-5540 3010);
FORCEPROP 1 LASTPIN (-5550 3000) BN 29
J 0
(-5602 3008);
DISPLAY 0.617021 (-5602 3008);
PAINT PINK (-5602 3008);
FORCEPROP 2 LAST CDS_LIB mstr_standard
J 0
(-5600 3000);
PAINT MONO (-5600 3000);
DISPLAY INVISIBLE (-5600 3000);
FORCEPROP 1 LAST PATH I51
J 0
(-5602 3000);
DISPLAY 0.872340 (-5602 3000);
PAINT GREEN (-5602 3000);
DISPLAY INVISIBLE (-5602 3000);
FORCEPROP 1 LAST BODY_TYPE PLUMBING
J 0
(-5600 2950);
DISPLAY 1.595745 (-5600 2950);
PAINT GREEN (-5600 2950);
DISPLAY INVISIBLE (-5600 2950);
FORCEPROP 1 LAST HDL_TAP TRUE
J 0
(-5275 2875);
DISPLAY 1.595745 (-5275 2875);
PAINT GREEN (-5275 2875);
DISPLAY INVISIBLE (-5275 2875);
FORCEADD TAP..6
(-5600 3100);
FORCEPROP 3 LASTPIN (-5550 3100) SIG_NAME M_A_DQ<31>
J 0
(-5540 3110);
DISPLAY 0.659574 (-5540 3110);
PAINT MONO (-5540 3110);
DISPLAY INVISIBLE (-5540 3110);
FORCEPROP 1 LASTPIN (-5550 3100) BN 31
J 0
(-5602 3108);
DISPLAY 0.617021 (-5602 3108);
PAINT PINK (-5602 3108);
FORCEPROP 2 LAST CDS_LIB mstr_standard
J 0
(-5600 3100);
PAINT MONO (-5600 3100);
DISPLAY INVISIBLE (-5600 3100);
FORCEPROP 1 LAST PATH I52
J 0
(-5602 3100);
DISPLAY 0.872340 (-5602 3100);
PAINT GREEN (-5602 3100);
DISPLAY INVISIBLE (-5602 3100);
FORCEPROP 1 LAST BODY_TYPE PLUMBING
J 0
(-5600 3050);
DISPLAY 1.595745 (-5600 3050);
PAINT GREEN (-5600 3050);
DISPLAY INVISIBLE (-5600 3050);
FORCEPROP 1 LAST HDL_TAP TRUE
J 0
(-5275 2975);
DISPLAY 1.595745 (-5275 2975);
PAINT GREEN (-5275 2975);
DISPLAY INVISIBLE (-5275 2975);
FORCEADD TAP..6
(-5600 3050);
FORCEPROP 3 LASTPIN (-5550 3050) SIG_NAME M_A_DQ<30>
J 0
(-5540 3060);
DISPLAY 0.659574 (-5540 3060);
PAINT MONO (-5540 3060);
DISPLAY INVISIBLE (-5540 3060);
FORCEPROP 1 LASTPIN (-5550 3050) BN 30
J 0
(-5602 3058);
DISPLAY 0.617021 (-5602 3058);
PAINT PINK (-5602 3058);
FORCEPROP 2 LAST CDS_LIB mstr_standard
J 0
(-5600 3050);
PAINT MONO (-5600 3050);
DISPLAY INVISIBLE (-5600 3050);
FORCEPROP 1 LAST PATH I53
J 0
(-5602 3050);
DISPLAY 0.872340 (-5602 3050);
PAINT GREEN (-5602 3050);
DISPLAY INVISIBLE (-5602 3050);
FORCEPROP 1 LAST BODY_TYPE PLUMBING
J 0
(-5600 3000);
DISPLAY 1.595745 (-5600 3000);
PAINT GREEN (-5600 3000);
DISPLAY INVISIBLE (-5600 3000);
FORCEPROP 1 LAST HDL_TAP TRUE
J 0
(-5275 2925);
DISPLAY 1.595745 (-5275 2925);
PAINT GREEN (-5275 2925);
DISPLAY INVISIBLE (-5275 2925);
FORCEADD TAP..6
(-5600 3150);
FORCEPROP 3 LASTPIN (-5550 3150) SIG_NAME M_A_DQ<32>
J 0
(-5540 3160);
DISPLAY 0.659574 (-5540 3160);
PAINT MONO (-5540 3160);
DISPLAY INVISIBLE (-5540 3160);
FORCEPROP 1 LASTPIN (-5550 3150) BN 32
J 0
(-5602 3158);
DISPLAY 0.617021 (-5602 3158);
PAINT PINK (-5602 3158);
FORCEPROP 2 LAST CDS_LIB mstr_standard
J 0
(-5600 3150);
PAINT MONO (-5600 3150);
DISPLAY INVISIBLE (-5600 3150);
FORCEPROP 1 LAST PATH I54
J 0
(-5602 3150);
DISPLAY 0.872340 (-5602 3150);
PAINT GREEN (-5602 3150);
DISPLAY INVISIBLE (-5602 3150);
FORCEPROP 1 LAST BODY_TYPE PLUMBING
J 0
(-5600 3100);
DISPLAY 1.595745 (-5600 3100);
PAINT GREEN (-5600 3100);
DISPLAY INVISIBLE (-5600 3100);
FORCEPROP 1 LAST HDL_TAP TRUE
J 0
(-5275 3025);
DISPLAY 1.595745 (-5275 3025);
PAINT GREEN (-5275 3025);
DISPLAY INVISIBLE (-5275 3025);
FORCEADD TAP..6
(-5600 3200);
FORCEPROP 3 LASTPIN (-5550 3200) SIG_NAME M_A_DQ<33>
J 0
(-5540 3210);
DISPLAY 0.659574 (-5540 3210);
PAINT MONO (-5540 3210);
DISPLAY INVISIBLE (-5540 3210);
FORCEPROP 1 LASTPIN (-5550 3200) BN 33
J 0
(-5602 3208);
DISPLAY 0.617021 (-5602 3208);
PAINT PINK (-5602 3208);
FORCEPROP 2 LAST CDS_LIB mstr_standard
J 0
(-5600 3200);
PAINT MONO (-5600 3200);
DISPLAY INVISIBLE (-5600 3200);
FORCEPROP 1 LAST PATH I55
J 0
(-5602 3200);
DISPLAY 0.872340 (-5602 3200);
PAINT GREEN (-5602 3200);
DISPLAY INVISIBLE (-5602 3200);
FORCEPROP 1 LAST BODY_TYPE PLUMBING
J 0
(-5600 3150);
DISPLAY 1.595745 (-5600 3150);
PAINT GREEN (-5600 3150);
DISPLAY INVISIBLE (-5600 3150);
FORCEPROP 1 LAST HDL_TAP TRUE
J 0
(-5275 3075);
DISPLAY 1.595745 (-5275 3075);
PAINT GREEN (-5275 3075);
DISPLAY INVISIBLE (-5275 3075);
FORCEADD TAP..6
(-5600 3250);
FORCEPROP 3 LASTPIN (-5550 3250) SIG_NAME M_A_DQ<34>
J 0
(-5540 3260);
DISPLAY 0.659574 (-5540 3260);
PAINT MONO (-5540 3260);
DISPLAY INVISIBLE (-5540 3260);
FORCEPROP 1 LASTPIN (-5550 3250) BN 34
J 0
(-5602 3258);
DISPLAY 0.617021 (-5602 3258);
PAINT PINK (-5602 3258);
FORCEPROP 2 LAST CDS_LIB mstr_standard
J 0
(-5600 3250);
PAINT MONO (-5600 3250);
DISPLAY INVISIBLE (-5600 3250);
FORCEPROP 1 LAST PATH I56
J 0
(-5602 3250);
DISPLAY 0.872340 (-5602 3250);
PAINT GREEN (-5602 3250);
DISPLAY INVISIBLE (-5602 3250);
FORCEPROP 1 LAST BODY_TYPE PLUMBING
J 0
(-5600 3200);
DISPLAY 1.595745 (-5600 3200);
PAINT GREEN (-5600 3200);
DISPLAY INVISIBLE (-5600 3200);
FORCEPROP 1 LAST HDL_TAP TRUE
J 0
(-5275 3125);
DISPLAY 1.595745 (-5275 3125);
PAINT GREEN (-5275 3125);
DISPLAY INVISIBLE (-5275 3125);
FORCEADD TAP..6
(-5600 3350);
FORCEPROP 3 LASTPIN (-5550 3350) SIG_NAME M_A_DQ<36>
J 0
(-5540 3360);
DISPLAY 0.659574 (-5540 3360);
PAINT MONO (-5540 3360);
DISPLAY INVISIBLE (-5540 3360);
FORCEPROP 1 LASTPIN (-5550 3350) BN 36
J 0
(-5602 3358);
DISPLAY 0.617021 (-5602 3358);
PAINT PINK (-5602 3358);
FORCEPROP 2 LAST CDS_LIB mstr_standard
J 0
(-5600 3350);
PAINT MONO (-5600 3350);
DISPLAY INVISIBLE (-5600 3350);
FORCEPROP 1 LAST PATH I57
J 0
(-5602 3350);
DISPLAY 0.872340 (-5602 3350);
PAINT GREEN (-5602 3350);
DISPLAY INVISIBLE (-5602 3350);
FORCEPROP 1 LAST BODY_TYPE PLUMBING
J 0
(-5600 3300);
DISPLAY 1.595745 (-5600 3300);
PAINT GREEN (-5600 3300);
DISPLAY INVISIBLE (-5600 3300);
FORCEPROP 1 LAST HDL_TAP TRUE
J 0
(-5275 3225);
DISPLAY 1.595745 (-5275 3225);
PAINT GREEN (-5275 3225);
DISPLAY INVISIBLE (-5275 3225);
FORCEADD TAP..6
(-5600 3300);
FORCEPROP 3 LASTPIN (-5550 3300) SIG_NAME M_A_DQ<35>
J 0
(-5540 3310);
DISPLAY 0.659574 (-5540 3310);
PAINT MONO (-5540 3310);
DISPLAY INVISIBLE (-5540 3310);
FORCEPROP 1 LASTPIN (-5550 3300) BN 35
J 0
(-5602 3308);
DISPLAY 0.617021 (-5602 3308);
PAINT PINK (-5602 3308);
FORCEPROP 2 LAST CDS_LIB mstr_standard
J 0
(-5600 3300);
PAINT MONO (-5600 3300);
DISPLAY INVISIBLE (-5600 3300);
FORCEPROP 1 LAST PATH I58
J 0
(-5602 3300);
DISPLAY 0.872340 (-5602 3300);
PAINT GREEN (-5602 3300);
DISPLAY INVISIBLE (-5602 3300);
FORCEPROP 1 LAST BODY_TYPE PLUMBING
J 0
(-5600 3250);
DISPLAY 1.595745 (-5600 3250);
PAINT GREEN (-5600 3250);
DISPLAY INVISIBLE (-5600 3250);
FORCEPROP 1 LAST HDL_TAP TRUE
J 0
(-5275 3175);
DISPLAY 1.595745 (-5275 3175);
PAINT GREEN (-5275 3175);
DISPLAY INVISIBLE (-5275 3175);
FORCEADD TAP..6
(-5600 3400);
FORCEPROP 3 LASTPIN (-5550 3400) SIG_NAME M_A_DQ<37>
J 0
(-5540 3410);
DISPLAY 0.659574 (-5540 3410);
PAINT MONO (-5540 3410);
DISPLAY INVISIBLE (-5540 3410);
FORCEPROP 1 LASTPIN (-5550 3400) BN 37
J 0
(-5602 3408);
DISPLAY 0.617021 (-5602 3408);
PAINT PINK (-5602 3408);
FORCEPROP 2 LAST CDS_LIB mstr_standard
J 0
(-5600 3400);
PAINT MONO (-5600 3400);
DISPLAY INVISIBLE (-5600 3400);
FORCEPROP 1 LAST PATH I59
J 0
(-5602 3400);
DISPLAY 0.872340 (-5602 3400);
PAINT GREEN (-5602 3400);
DISPLAY INVISIBLE (-5602 3400);
FORCEPROP 1 LAST BODY_TYPE PLUMBING
J 0
(-5600 3350);
DISPLAY 1.595745 (-5600 3350);
PAINT GREEN (-5600 3350);
DISPLAY INVISIBLE (-5600 3350);
FORCEPROP 1 LAST HDL_TAP TRUE
J 0
(-5275 3275);
DISPLAY 1.595745 (-5275 3275);
PAINT GREEN (-5275 3275);
DISPLAY INVISIBLE (-5275 3275);
FORCEADD TAP..6
(-5600 700);
FORCEPROP 3 LASTPIN (-5550 700) SIG_NAME M_A_CLK_DN<1>
J 0
(-5540 710);
DISPLAY 0.659574 (-5540 710);
PAINT MONO (-5540 710);
DISPLAY INVISIBLE (-5540 710);
FORCEPROP 1 LASTPIN (-5550 700) BN 1
J 0
(-5602 708);
DISPLAY 0.617021 (-5602 708);
PAINT PINK (-5602 708);
FORCEPROP 2 LAST CDS_LIB mstr_standard
J 0
(-5600 700);
PAINT MONO (-5600 700);
DISPLAY INVISIBLE (-5600 700);
FORCEPROP 1 LAST PATH I6
J 0
(-5602 700);
DISPLAY 0.872340 (-5602 700);
PAINT GREEN (-5602 700);
DISPLAY INVISIBLE (-5602 700);
FORCEPROP 1 LAST BODY_TYPE PLUMBING
J 0
(-5600 650);
DISPLAY 1.595745 (-5600 650);
PAINT GREEN (-5600 650);
DISPLAY INVISIBLE (-5600 650);
FORCEPROP 1 LAST HDL_TAP TRUE
J 0
(-5275 575);
DISPLAY 1.595745 (-5275 575);
PAINT GREEN (-5275 575);
DISPLAY INVISIBLE (-5275 575);
FORCEADD TAP..6
(-5600 3450);
FORCEPROP 3 LASTPIN (-5550 3450) SIG_NAME M_A_DQ<38>
J 0
(-5540 3460);
DISPLAY 0.659574 (-5540 3460);
PAINT MONO (-5540 3460);
DISPLAY INVISIBLE (-5540 3460);
FORCEPROP 1 LASTPIN (-5550 3450) BN 38
J 0
(-5602 3458);
DISPLAY 0.617021 (-5602 3458);
PAINT PINK (-5602 3458);
FORCEPROP 2 LAST CDS_LIB mstr_standard
J 0
(-5600 3450);
PAINT MONO (-5600 3450);
DISPLAY INVISIBLE (-5600 3450);
FORCEPROP 1 LAST PATH I60
J 0
(-5602 3450);
DISPLAY 0.872340 (-5602 3450);
PAINT GREEN (-5602 3450);
DISPLAY INVISIBLE (-5602 3450);
FORCEPROP 1 LAST BODY_TYPE PLUMBING
J 0
(-5600 3400);
DISPLAY 1.595745 (-5600 3400);
PAINT GREEN (-5600 3400);
DISPLAY INVISIBLE (-5600 3400);
FORCEPROP 1 LAST HDL_TAP TRUE
J 0
(-5275 3325);
DISPLAY 1.595745 (-5275 3325);
PAINT GREEN (-5275 3325);
DISPLAY INVISIBLE (-5275 3325);
FORCEADD TAP..6
(-5600 3500);
FORCEPROP 3 LASTPIN (-5550 3500) SIG_NAME M_A_DQ<39>
J 0
(-5540 3510);
DISPLAY 0.659574 (-5540 3510);
PAINT MONO (-5540 3510);
DISPLAY INVISIBLE (-5540 3510);
FORCEPROP 1 LASTPIN (-5550 3500) BN 39
J 0
(-5602 3508);
DISPLAY 0.617021 (-5602 3508);
PAINT PINK (-5602 3508);
FORCEPROP 2 LAST CDS_LIB mstr_standard
J 0
(-5600 3500);
PAINT MONO (-5600 3500);
DISPLAY INVISIBLE (-5600 3500);
FORCEPROP 1 LAST PATH I61
J 0
(-5602 3500);
DISPLAY 0.872340 (-5602 3500);
PAINT GREEN (-5602 3500);
DISPLAY INVISIBLE (-5602 3500);
FORCEPROP 1 LAST BODY_TYPE PLUMBING
J 0
(-5600 3450);
DISPLAY 1.595745 (-5600 3450);
PAINT GREEN (-5600 3450);
DISPLAY INVISIBLE (-5600 3450);
FORCEPROP 1 LAST HDL_TAP TRUE
J 0
(-5275 3375);
DISPLAY 1.595745 (-5275 3375);
PAINT GREEN (-5275 3375);
DISPLAY INVISIBLE (-5275 3375);
FORCEADD TAP..6
(-5600 3550);
FORCEPROP 3 LASTPIN (-5550 3550) SIG_NAME M_A_DQ<40>
J 0
(-5540 3560);
DISPLAY 0.659574 (-5540 3560);
PAINT MONO (-5540 3560);
DISPLAY INVISIBLE (-5540 3560);
FORCEPROP 1 LASTPIN (-5550 3550) BN 40
J 0
(-5602 3558);
DISPLAY 0.617021 (-5602 3558);
PAINT PINK (-5602 3558);
FORCEPROP 2 LAST CDS_LIB mstr_standard
J 0
(-5600 3550);
PAINT MONO (-5600 3550);
DISPLAY INVISIBLE (-5600 3550);
FORCEPROP 1 LAST PATH I62
J 0
(-5602 3550);
DISPLAY 0.872340 (-5602 3550);
PAINT GREEN (-5602 3550);
DISPLAY INVISIBLE (-5602 3550);
FORCEPROP 1 LAST BODY_TYPE PLUMBING
J 0
(-5600 3500);
DISPLAY 1.595745 (-5600 3500);
PAINT GREEN (-5600 3500);
DISPLAY INVISIBLE (-5600 3500);
FORCEPROP 1 LAST HDL_TAP TRUE
J 0
(-5275 3425);
DISPLAY 1.595745 (-5275 3425);
PAINT GREEN (-5275 3425);
DISPLAY INVISIBLE (-5275 3425);
FORCEADD TAP..6
(-5600 3600);
FORCEPROP 3 LASTPIN (-5550 3600) SIG_NAME M_A_DQ<41>
J 0
(-5540 3610);
DISPLAY 0.659574 (-5540 3610);
PAINT MONO (-5540 3610);
DISPLAY INVISIBLE (-5540 3610);
FORCEPROP 1 LASTPIN (-5550 3600) BN 41
J 0
(-5602 3608);
DISPLAY 0.617021 (-5602 3608);
PAINT PINK (-5602 3608);
FORCEPROP 2 LAST CDS_LIB mstr_standard
J 0
(-5600 3600);
PAINT MONO (-5600 3600);
DISPLAY INVISIBLE (-5600 3600);
FORCEPROP 1 LAST PATH I63
J 0
(-5602 3600);
DISPLAY 0.872340 (-5602 3600);
PAINT GREEN (-5602 3600);
DISPLAY INVISIBLE (-5602 3600);
FORCEPROP 1 LAST BODY_TYPE PLUMBING
J 0
(-5600 3550);
DISPLAY 1.595745 (-5600 3550);
PAINT GREEN (-5600 3550);
DISPLAY INVISIBLE (-5600 3550);
FORCEPROP 1 LAST HDL_TAP TRUE
J 0
(-5275 3475);
DISPLAY 1.595745 (-5275 3475);
PAINT GREEN (-5275 3475);
DISPLAY INVISIBLE (-5275 3475);
FORCEADD TAP..6
(-5600 3650);
FORCEPROP 3 LASTPIN (-5550 3650) SIG_NAME M_A_DQ<42>
J 0
(-5540 3660);
DISPLAY 0.659574 (-5540 3660);
PAINT MONO (-5540 3660);
DISPLAY INVISIBLE (-5540 3660);
FORCEPROP 1 LASTPIN (-5550 3650) BN 42
J 0
(-5602 3658);
DISPLAY 0.617021 (-5602 3658);
PAINT PINK (-5602 3658);
FORCEPROP 2 LAST CDS_LIB mstr_standard
J 0
(-5600 3650);
PAINT MONO (-5600 3650);
DISPLAY INVISIBLE (-5600 3650);
FORCEPROP 1 LAST PATH I64
J 0
(-5602 3650);
DISPLAY 0.872340 (-5602 3650);
PAINT GREEN (-5602 3650);
DISPLAY INVISIBLE (-5602 3650);
FORCEPROP 1 LAST BODY_TYPE PLUMBING
J 0
(-5600 3600);
DISPLAY 1.595745 (-5600 3600);
PAINT GREEN (-5600 3600);
DISPLAY INVISIBLE (-5600 3600);
FORCEPROP 1 LAST HDL_TAP TRUE
J 0
(-5275 3525);
DISPLAY 1.595745 (-5275 3525);
PAINT GREEN (-5275 3525);
DISPLAY INVISIBLE (-5275 3525);
FORCEADD TAP..6
(-5600 3700);
FORCEPROP 3 LASTPIN (-5550 3700) SIG_NAME M_A_DQ<43>
J 0
(-5540 3710);
DISPLAY 0.659574 (-5540 3710);
PAINT MONO (-5540 3710);
DISPLAY INVISIBLE (-5540 3710);
FORCEPROP 1 LASTPIN (-5550 3700) BN 43
J 0
(-5602 3708);
DISPLAY 0.617021 (-5602 3708);
PAINT PINK (-5602 3708);
FORCEPROP 2 LAST CDS_LIB mstr_standard
J 0
(-5600 3700);
PAINT MONO (-5600 3700);
DISPLAY INVISIBLE (-5600 3700);
FORCEPROP 1 LAST PATH I65
J 0
(-5602 3700);
DISPLAY 0.872340 (-5602 3700);
PAINT GREEN (-5602 3700);
DISPLAY INVISIBLE (-5602 3700);
FORCEPROP 1 LAST BODY_TYPE PLUMBING
J 0
(-5600 3650);
DISPLAY 1.595745 (-5600 3650);
PAINT GREEN (-5600 3650);
DISPLAY INVISIBLE (-5600 3650);
FORCEPROP 1 LAST HDL_TAP TRUE
J 0
(-5275 3575);
DISPLAY 1.595745 (-5275 3575);
PAINT GREEN (-5275 3575);
DISPLAY INVISIBLE (-5275 3575);
FORCEADD TAP..6
(-5600 3750);
FORCEPROP 3 LASTPIN (-5550 3750) SIG_NAME M_A_DQ<44>
J 0
(-5540 3760);
DISPLAY 0.659574 (-5540 3760);
PAINT MONO (-5540 3760);
DISPLAY INVISIBLE (-5540 3760);
FORCEPROP 1 LASTPIN (-5550 3750) BN 44
J 0
(-5602 3758);
DISPLAY 0.617021 (-5602 3758);
PAINT PINK (-5602 3758);
FORCEPROP 2 LAST CDS_LIB mstr_standard
J 0
(-5600 3750);
PAINT MONO (-5600 3750);
DISPLAY INVISIBLE (-5600 3750);
FORCEPROP 1 LAST PATH I66
J 0
(-5602 3750);
DISPLAY 0.872340 (-5602 3750);
PAINT GREEN (-5602 3750);
DISPLAY INVISIBLE (-5602 3750);
FORCEPROP 1 LAST BODY_TYPE PLUMBING
J 0
(-5600 3700);
DISPLAY 1.595745 (-5600 3700);
PAINT GREEN (-5600 3700);
DISPLAY INVISIBLE (-5600 3700);
FORCEPROP 1 LAST HDL_TAP TRUE
J 0
(-5275 3625);
DISPLAY 1.595745 (-5275 3625);
PAINT GREEN (-5275 3625);
DISPLAY INVISIBLE (-5275 3625);
FORCEADD TAP..6
(-5600 3800);
FORCEPROP 3 LASTPIN (-5550 3800) SIG_NAME M_A_DQ<45>
J 0
(-5540 3810);
DISPLAY 0.659574 (-5540 3810);
PAINT MONO (-5540 3810);
DISPLAY INVISIBLE (-5540 3810);
FORCEPROP 1 LASTPIN (-5550 3800) BN 45
J 0
(-5602 3808);
DISPLAY 0.617021 (-5602 3808);
PAINT PINK (-5602 3808);
FORCEPROP 2 LAST CDS_LIB mstr_standard
J 0
(-5600 3800);
PAINT MONO (-5600 3800);
DISPLAY INVISIBLE (-5600 3800);
FORCEPROP 1 LAST PATH I67
J 0
(-5602 3800);
DISPLAY 0.872340 (-5602 3800);
PAINT GREEN (-5602 3800);
DISPLAY INVISIBLE (-5602 3800);
FORCEPROP 1 LAST BODY_TYPE PLUMBING
J 0
(-5600 3750);
DISPLAY 1.595745 (-5600 3750);
PAINT GREEN (-5600 3750);
DISPLAY INVISIBLE (-5600 3750);
FORCEPROP 1 LAST HDL_TAP TRUE
J 0
(-5275 3675);
DISPLAY 1.595745 (-5275 3675);
PAINT GREEN (-5275 3675);
DISPLAY INVISIBLE (-5275 3675);
FORCEADD TAP..6
(-5600 3850);
FORCEPROP 3 LASTPIN (-5550 3850) SIG_NAME M_A_DQ<46>
J 0
(-5540 3860);
DISPLAY 0.659574 (-5540 3860);
PAINT MONO (-5540 3860);
DISPLAY INVISIBLE (-5540 3860);
FORCEPROP 1 LASTPIN (-5550 3850) BN 46
J 0
(-5602 3858);
DISPLAY 0.617021 (-5602 3858);
PAINT PINK (-5602 3858);
FORCEPROP 2 LAST CDS_LIB mstr_standard
J 0
(-5600 3850);
PAINT MONO (-5600 3850);
DISPLAY INVISIBLE (-5600 3850);
FORCEPROP 1 LAST PATH I68
J 0
(-5602 3850);
DISPLAY 0.872340 (-5602 3850);
PAINT GREEN (-5602 3850);
DISPLAY INVISIBLE (-5602 3850);
FORCEPROP 1 LAST BODY_TYPE PLUMBING
J 0
(-5600 3800);
DISPLAY 1.595745 (-5600 3800);
PAINT GREEN (-5600 3800);
DISPLAY INVISIBLE (-5600 3800);
FORCEPROP 1 LAST HDL_TAP TRUE
J 0
(-5275 3725);
DISPLAY 1.595745 (-5275 3725);
PAINT GREEN (-5275 3725);
DISPLAY INVISIBLE (-5275 3725);
FORCEADD TAP..6
(-5600 3900);
FORCEPROP 3 LASTPIN (-5550 3900) SIG_NAME M_A_DQ<47>
J 0
(-5540 3910);
DISPLAY 0.659574 (-5540 3910);
PAINT MONO (-5540 3910);
DISPLAY INVISIBLE (-5540 3910);
FORCEPROP 1 LASTPIN (-5550 3900) BN 47
J 0
(-5602 3908);
DISPLAY 0.617021 (-5602 3908);
PAINT PINK (-5602 3908);
FORCEPROP 2 LAST CDS_LIB mstr_standard
J 0
(-5600 3900);
PAINT MONO (-5600 3900);
DISPLAY INVISIBLE (-5600 3900);
FORCEPROP 1 LAST PATH I69
J 0
(-5602 3900);
DISPLAY 0.872340 (-5602 3900);
PAINT GREEN (-5602 3900);
DISPLAY INVISIBLE (-5602 3900);
FORCEPROP 1 LAST BODY_TYPE PLUMBING
J 0
(-5600 3850);
DISPLAY 1.595745 (-5600 3850);
PAINT GREEN (-5600 3850);
DISPLAY INVISIBLE (-5600 3850);
FORCEPROP 1 LAST HDL_TAP TRUE
J 0
(-5275 3775);
DISPLAY 1.595745 (-5275 3775);
PAINT GREEN (-5275 3775);
DISPLAY INVISIBLE (-5275 3775);
FORCEADD TAP..6
(-5600 800);
FORCEPROP 3 LASTPIN (-5550 800) SIG_NAME M_A_CLK_DN<3>
J 0
(-5540 810);
DISPLAY 0.659574 (-5540 810);
PAINT MONO (-5540 810);
DISPLAY INVISIBLE (-5540 810);
FORCEPROP 1 LASTPIN (-5550 800) BN 3
J 0
(-5602 808);
DISPLAY 0.617021 (-5602 808);
PAINT PINK (-5602 808);
FORCEPROP 2 LAST CDS_LIB mstr_standard
J 0
(-5600 800);
PAINT MONO (-5600 800);
DISPLAY INVISIBLE (-5600 800);
FORCEPROP 1 LAST PATH I7
J 0
(-5602 800);
DISPLAY 0.872340 (-5602 800);
PAINT GREEN (-5602 800);
DISPLAY INVISIBLE (-5602 800);
FORCEPROP 1 LAST BODY_TYPE PLUMBING
J 0
(-5600 750);
DISPLAY 1.595745 (-5600 750);
PAINT GREEN (-5600 750);
DISPLAY INVISIBLE (-5600 750);
FORCEPROP 1 LAST HDL_TAP TRUE
J 0
(-5275 675);
DISPLAY 1.595745 (-5275 675);
PAINT GREEN (-5275 675);
DISPLAY INVISIBLE (-5275 675);
FORCEADD TAP..6
(-5600 3950);
FORCEPROP 3 LASTPIN (-5550 3950) SIG_NAME M_A_DQ<48>
J 0
(-5540 3960);
DISPLAY 0.659574 (-5540 3960);
PAINT MONO (-5540 3960);
DISPLAY INVISIBLE (-5540 3960);
FORCEPROP 1 LASTPIN (-5550 3950) BN 48
J 0
(-5602 3958);
DISPLAY 0.617021 (-5602 3958);
PAINT PINK (-5602 3958);
FORCEPROP 2 LAST CDS_LIB mstr_standard
J 0
(-5600 3950);
PAINT MONO (-5600 3950);
DISPLAY INVISIBLE (-5600 3950);
FORCEPROP 1 LAST PATH I70
J 0
(-5602 3950);
DISPLAY 0.872340 (-5602 3950);
PAINT GREEN (-5602 3950);
DISPLAY INVISIBLE (-5602 3950);
FORCEPROP 1 LAST BODY_TYPE PLUMBING
J 0
(-5600 3900);
DISPLAY 1.595745 (-5600 3900);
PAINT GREEN (-5600 3900);
DISPLAY INVISIBLE (-5600 3900);
FORCEPROP 1 LAST HDL_TAP TRUE
J 0
(-5275 3825);
DISPLAY 1.595745 (-5275 3825);
PAINT GREEN (-5275 3825);
DISPLAY INVISIBLE (-5275 3825);
FORCEADD TAP..6
(-5600 4000);
FORCEPROP 3 LASTPIN (-5550 4000) SIG_NAME M_A_DQ<49>
J 0
(-5540 4010);
DISPLAY 0.659574 (-5540 4010);
PAINT MONO (-5540 4010);
DISPLAY INVISIBLE (-5540 4010);
FORCEPROP 1 LASTPIN (-5550 4000) BN 49
J 0
(-5602 4008);
DISPLAY 0.617021 (-5602 4008);
PAINT PINK (-5602 4008);
FORCEPROP 2 LAST CDS_LIB mstr_standard
J 0
(-5600 4000);
PAINT MONO (-5600 4000);
DISPLAY INVISIBLE (-5600 4000);
FORCEPROP 1 LAST PATH I71
J 0
(-5602 4000);
DISPLAY 0.872340 (-5602 4000);
PAINT GREEN (-5602 4000);
DISPLAY INVISIBLE (-5602 4000);
FORCEPROP 1 LAST BODY_TYPE PLUMBING
J 0
(-5600 3950);
DISPLAY 1.595745 (-5600 3950);
PAINT GREEN (-5600 3950);
DISPLAY INVISIBLE (-5600 3950);
FORCEPROP 1 LAST HDL_TAP TRUE
J 0
(-5275 3875);
DISPLAY 1.595745 (-5275 3875);
PAINT GREEN (-5275 3875);
DISPLAY INVISIBLE (-5275 3875);
FORCEADD OFFPAGE..6
(-6450 4825);
FORCEPROP 2 LAST $XR1 44 
J 0
(-6789 4825);
DISPLAY 0.638298 (-6789 4825);
PAINT MONO (-6789 4825);
FORCEPROP 2 LAST $XR0 43 
J 0
(-6699 4825);
DISPLAY 0.638298 (-6699 4825);
PAINT MONO (-6699 4825);
FORCEPROP 2 LAST CDS_LIB mstr_standard
J 0
(-6450 4825);
PAINT MONO (-6450 4825);
DISPLAY INVISIBLE (-6450 4825);
FORCEPROP 2 LAST PATH I72
J 0
(-6400 4900);
DISPLAY 1.021277 (-6400 4900);
PAINT ORANGE (-6400 4900);
DISPLAY INVISIBLE (-6400 4900);
FORCEPROP 1 LAST OFFPAGE TRUE
J 0
(-6125 4700);
DISPLAY 1.170213 (-6125 4700);
PAINT GREEN (-6125 4700);
DISPLAY INVISIBLE (-6125 4700);
FORCEPROP 1 LAST COMMENT_BODY TRUE
J 0
(-6350 4750);
DISPLAY 1.170213 (-6350 4750);
PAINT GREEN (-6350 4750);
DISPLAY INVISIBLE (-6350 4750);
FORCEADD TAP..6
(-5600 4050);
FORCEPROP 3 LASTPIN (-5550 4050) SIG_NAME M_A_DQ<50>
J 0
(-5540 4060);
DISPLAY 0.659574 (-5540 4060);
PAINT MONO (-5540 4060);
DISPLAY INVISIBLE (-5540 4060);
FORCEPROP 1 LASTPIN (-5550 4050) BN 50
J 0
(-5602 4058);
DISPLAY 0.617021 (-5602 4058);
PAINT PINK (-5602 4058);
FORCEPROP 2 LAST CDS_LIB mstr_standard
J 0
(-5600 4050);
PAINT MONO (-5600 4050);
DISPLAY INVISIBLE (-5600 4050);
FORCEPROP 1 LAST PATH I73
J 0
(-5602 4050);
DISPLAY 0.872340 (-5602 4050);
PAINT GREEN (-5602 4050);
DISPLAY INVISIBLE (-5602 4050);
FORCEPROP 1 LAST BODY_TYPE PLUMBING
J 0
(-5600 4000);
DISPLAY 1.595745 (-5600 4000);
PAINT GREEN (-5600 4000);
DISPLAY INVISIBLE (-5600 4000);
FORCEPROP 1 LAST HDL_TAP TRUE
J 0
(-5275 3925);
DISPLAY 1.595745 (-5275 3925);
PAINT GREEN (-5275 3925);
DISPLAY INVISIBLE (-5275 3925);
FORCEADD TAP..6
(-5600 4100);
FORCEPROP 3 LASTPIN (-5550 4100) SIG_NAME M_A_DQ<51>
J 0
(-5540 4110);
DISPLAY 0.659574 (-5540 4110);
PAINT MONO (-5540 4110);
DISPLAY INVISIBLE (-5540 4110);
FORCEPROP 1 LASTPIN (-5550 4100) BN 51
J 0
(-5602 4108);
DISPLAY 0.617021 (-5602 4108);
PAINT PINK (-5602 4108);
FORCEPROP 2 LAST CDS_LIB mstr_standard
J 0
(-5600 4100);
PAINT MONO (-5600 4100);
DISPLAY INVISIBLE (-5600 4100);
FORCEPROP 1 LAST PATH I74
J 0
(-5602 4100);
DISPLAY 0.872340 (-5602 4100);
PAINT GREEN (-5602 4100);
DISPLAY INVISIBLE (-5602 4100);
FORCEPROP 1 LAST BODY_TYPE PLUMBING
J 0
(-5600 4050);
DISPLAY 1.595745 (-5600 4050);
PAINT GREEN (-5600 4050);
DISPLAY INVISIBLE (-5600 4050);
FORCEPROP 1 LAST HDL_TAP TRUE
J 0
(-5275 3975);
DISPLAY 1.595745 (-5275 3975);
PAINT GREEN (-5275 3975);
DISPLAY INVISIBLE (-5275 3975);
FORCEADD TAP..6
(-5600 4150);
FORCEPROP 3 LASTPIN (-5550 4150) SIG_NAME M_A_DQ<52>
J 0
(-5540 4160);
DISPLAY 0.659574 (-5540 4160);
PAINT MONO (-5540 4160);
DISPLAY INVISIBLE (-5540 4160);
FORCEPROP 1 LASTPIN (-5550 4150) BN 52
J 0
(-5602 4158);
DISPLAY 0.617021 (-5602 4158);
PAINT PINK (-5602 4158);
FORCEPROP 2 LAST CDS_LIB mstr_standard
J 0
(-5600 4150);
PAINT MONO (-5600 4150);
DISPLAY INVISIBLE (-5600 4150);
FORCEPROP 1 LAST PATH I75
J 0
(-5602 4150);
DISPLAY 0.872340 (-5602 4150);
PAINT GREEN (-5602 4150);
DISPLAY INVISIBLE (-5602 4150);
FORCEPROP 1 LAST BODY_TYPE PLUMBING
J 0
(-5600 4100);
DISPLAY 1.595745 (-5600 4100);
PAINT GREEN (-5600 4100);
DISPLAY INVISIBLE (-5600 4100);
FORCEPROP 1 LAST HDL_TAP TRUE
J 0
(-5275 4025);
DISPLAY 1.595745 (-5275 4025);
PAINT GREEN (-5275 4025);
DISPLAY INVISIBLE (-5275 4025);
FORCEADD TAP..6
(-5600 4200);
FORCEPROP 3 LASTPIN (-5550 4200) SIG_NAME M_A_DQ<53>
J 0
(-5540 4210);
DISPLAY 0.659574 (-5540 4210);
PAINT MONO (-5540 4210);
DISPLAY INVISIBLE (-5540 4210);
FORCEPROP 1 LASTPIN (-5550 4200) BN 53
J 0
(-5602 4208);
DISPLAY 0.617021 (-5602 4208);
PAINT PINK (-5602 4208);
FORCEPROP 2 LAST CDS_LIB mstr_standard
J 0
(-5600 4200);
PAINT MONO (-5600 4200);
DISPLAY INVISIBLE (-5600 4200);
FORCEPROP 1 LAST PATH I76
J 0
(-5602 4200);
DISPLAY 0.872340 (-5602 4200);
PAINT GREEN (-5602 4200);
DISPLAY INVISIBLE (-5602 4200);
FORCEPROP 1 LAST BODY_TYPE PLUMBING
J 0
(-5600 4150);
DISPLAY 1.595745 (-5600 4150);
PAINT GREEN (-5600 4150);
DISPLAY INVISIBLE (-5600 4150);
FORCEPROP 1 LAST HDL_TAP TRUE
J 0
(-5275 4075);
DISPLAY 1.595745 (-5275 4075);
PAINT GREEN (-5275 4075);
DISPLAY INVISIBLE (-5275 4075);
FORCEADD TAP..6
(-5600 4250);
FORCEPROP 3 LASTPIN (-5550 4250) SIG_NAME M_A_DQ<54>
J 0
(-5540 4260);
DISPLAY 0.659574 (-5540 4260);
PAINT MONO (-5540 4260);
DISPLAY INVISIBLE (-5540 4260);
FORCEPROP 1 LASTPIN (-5550 4250) BN 54
J 0
(-5602 4258);
DISPLAY 0.617021 (-5602 4258);
PAINT PINK (-5602 4258);
FORCEPROP 2 LAST CDS_LIB mstr_standard
J 0
(-5600 4250);
PAINT MONO (-5600 4250);
DISPLAY INVISIBLE (-5600 4250);
FORCEPROP 1 LAST PATH I77
J 0
(-5602 4250);
DISPLAY 0.872340 (-5602 4250);
PAINT GREEN (-5602 4250);
DISPLAY INVISIBLE (-5602 4250);
FORCEPROP 1 LAST BODY_TYPE PLUMBING
J 0
(-5600 4200);
DISPLAY 1.595745 (-5600 4200);
PAINT GREEN (-5600 4200);
DISPLAY INVISIBLE (-5600 4200);
FORCEPROP 1 LAST HDL_TAP TRUE
J 0
(-5275 4125);
DISPLAY 1.595745 (-5275 4125);
PAINT GREEN (-5275 4125);
DISPLAY INVISIBLE (-5275 4125);
FORCEADD TAP..6
(-5600 4300);
FORCEPROP 3 LASTPIN (-5550 4300) SIG_NAME M_A_DQ<55>
J 0
(-5540 4310);
DISPLAY 0.659574 (-5540 4310);
PAINT MONO (-5540 4310);
DISPLAY INVISIBLE (-5540 4310);
FORCEPROP 1 LASTPIN (-5550 4300) BN 55
J 0
(-5602 4308);
DISPLAY 0.617021 (-5602 4308);
PAINT PINK (-5602 4308);
FORCEPROP 2 LAST CDS_LIB mstr_standard
J 0
(-5600 4300);
PAINT MONO (-5600 4300);
DISPLAY INVISIBLE (-5600 4300);
FORCEPROP 1 LAST PATH I78
J 0
(-5602 4300);
DISPLAY 0.872340 (-5602 4300);
PAINT GREEN (-5602 4300);
DISPLAY INVISIBLE (-5602 4300);
FORCEPROP 1 LAST BODY_TYPE PLUMBING
J 0
(-5600 4250);
DISPLAY 1.595745 (-5600 4250);
PAINT GREEN (-5600 4250);
DISPLAY INVISIBLE (-5600 4250);
FORCEPROP 1 LAST HDL_TAP TRUE
J 0
(-5275 4175);
DISPLAY 1.595745 (-5275 4175);
PAINT GREEN (-5275 4175);
DISPLAY INVISIBLE (-5275 4175);
FORCEADD TAP..6
(-5600 4350);
FORCEPROP 3 LASTPIN (-5550 4350) SIG_NAME M_A_DQ<56>
J 0
(-5540 4360);
DISPLAY 0.659574 (-5540 4360);
PAINT MONO (-5540 4360);
DISPLAY INVISIBLE (-5540 4360);
FORCEPROP 1 LASTPIN (-5550 4350) BN 56
J 0
(-5602 4358);
DISPLAY 0.617021 (-5602 4358);
PAINT PINK (-5602 4358);
FORCEPROP 2 LAST CDS_LIB mstr_standard
J 0
(-5600 4350);
PAINT MONO (-5600 4350);
DISPLAY INVISIBLE (-5600 4350);
FORCEPROP 1 LAST PATH I79
J 0
(-5602 4350);
DISPLAY 0.872340 (-5602 4350);
PAINT GREEN (-5602 4350);
DISPLAY INVISIBLE (-5602 4350);
FORCEPROP 1 LAST BODY_TYPE PLUMBING
J 0
(-5600 4300);
DISPLAY 1.595745 (-5600 4300);
PAINT GREEN (-5600 4300);
DISPLAY INVISIBLE (-5600 4300);
FORCEPROP 1 LAST HDL_TAP TRUE
J 0
(-5275 4225);
DISPLAY 1.595745 (-5275 4225);
PAINT GREEN (-5275 4225);
DISPLAY INVISIBLE (-5275 4225);
FORCEADD TAP..6
(-5600 750);
FORCEPROP 3 LASTPIN (-5550 750) SIG_NAME M_A_CLK_DN<2>
J 0
(-5540 760);
DISPLAY 0.659574 (-5540 760);
PAINT MONO (-5540 760);
DISPLAY INVISIBLE (-5540 760);
FORCEPROP 1 LASTPIN (-5550 750) BN 2
J 0
(-5602 758);
DISPLAY 0.617021 (-5602 758);
PAINT PINK (-5602 758);
FORCEPROP 2 LAST CDS_LIB mstr_standard
J 0
(-5600 750);
PAINT MONO (-5600 750);
DISPLAY INVISIBLE (-5600 750);
FORCEPROP 1 LAST PATH I8
J 0
(-5602 750);
DISPLAY 0.872340 (-5602 750);
PAINT GREEN (-5602 750);
DISPLAY INVISIBLE (-5602 750);
FORCEPROP 1 LAST BODY_TYPE PLUMBING
J 0
(-5600 700);
DISPLAY 1.595745 (-5600 700);
PAINT GREEN (-5600 700);
DISPLAY INVISIBLE (-5600 700);
FORCEPROP 1 LAST HDL_TAP TRUE
J 0
(-5275 625);
DISPLAY 1.595745 (-5275 625);
PAINT GREEN (-5275 625);
DISPLAY INVISIBLE (-5275 625);
FORCEADD TAP..6
(-5600 4400);
FORCEPROP 3 LASTPIN (-5550 4400) SIG_NAME M_A_DQ<57>
J 0
(-5540 4410);
DISPLAY 0.659574 (-5540 4410);
PAINT MONO (-5540 4410);
DISPLAY INVISIBLE (-5540 4410);
FORCEPROP 1 LASTPIN (-5550 4400) BN 57
J 0
(-5602 4408);
DISPLAY 0.617021 (-5602 4408);
PAINT PINK (-5602 4408);
FORCEPROP 2 LAST CDS_LIB mstr_standard
J 0
(-5600 4400);
PAINT MONO (-5600 4400);
DISPLAY INVISIBLE (-5600 4400);
FORCEPROP 1 LAST PATH I80
J 0
(-5602 4400);
DISPLAY 0.872340 (-5602 4400);
PAINT GREEN (-5602 4400);
DISPLAY INVISIBLE (-5602 4400);
FORCEPROP 1 LAST BODY_TYPE PLUMBING
J 0
(-5600 4350);
DISPLAY 1.595745 (-5600 4350);
PAINT GREEN (-5600 4350);
DISPLAY INVISIBLE (-5600 4350);
FORCEPROP 1 LAST HDL_TAP TRUE
J 0
(-5275 4275);
DISPLAY 1.595745 (-5275 4275);
PAINT GREEN (-5275 4275);
DISPLAY INVISIBLE (-5275 4275);
FORCEADD TAP..6
(-5600 4450);
FORCEPROP 3 LASTPIN (-5550 4450) SIG_NAME M_A_DQ<58>
J 0
(-5540 4460);
DISPLAY 0.659574 (-5540 4460);
PAINT MONO (-5540 4460);
DISPLAY INVISIBLE (-5540 4460);
FORCEPROP 1 LASTPIN (-5550 4450) BN 58
J 0
(-5602 4458);
DISPLAY 0.617021 (-5602 4458);
PAINT PINK (-5602 4458);
FORCEPROP 2 LAST CDS_LIB mstr_standard
J 0
(-5600 4450);
PAINT MONO (-5600 4450);
DISPLAY INVISIBLE (-5600 4450);
FORCEPROP 1 LAST PATH I81
J 0
(-5602 4450);
DISPLAY 0.872340 (-5602 4450);
PAINT GREEN (-5602 4450);
DISPLAY INVISIBLE (-5602 4450);
FORCEPROP 1 LAST BODY_TYPE PLUMBING
J 0
(-5600 4400);
DISPLAY 1.595745 (-5600 4400);
PAINT GREEN (-5600 4400);
DISPLAY INVISIBLE (-5600 4400);
FORCEPROP 1 LAST HDL_TAP TRUE
J 0
(-5275 4325);
DISPLAY 1.595745 (-5275 4325);
PAINT GREEN (-5275 4325);
DISPLAY INVISIBLE (-5275 4325);
FORCEADD TAP..6
(-5600 4500);
FORCEPROP 3 LASTPIN (-5550 4500) SIG_NAME M_A_DQ<59>
J 0
(-5540 4510);
DISPLAY 0.659574 (-5540 4510);
PAINT MONO (-5540 4510);
DISPLAY INVISIBLE (-5540 4510);
FORCEPROP 1 LASTPIN (-5550 4500) BN 59
J 0
(-5602 4508);
DISPLAY 0.617021 (-5602 4508);
PAINT PINK (-5602 4508);
FORCEPROP 2 LAST CDS_LIB mstr_standard
J 0
(-5600 4500);
PAINT MONO (-5600 4500);
DISPLAY INVISIBLE (-5600 4500);
FORCEPROP 1 LAST PATH I82
J 0
(-5602 4500);
DISPLAY 0.872340 (-5602 4500);
PAINT GREEN (-5602 4500);
DISPLAY INVISIBLE (-5602 4500);
FORCEPROP 1 LAST BODY_TYPE PLUMBING
J 0
(-5600 4450);
DISPLAY 1.595745 (-5600 4450);
PAINT GREEN (-5600 4450);
DISPLAY INVISIBLE (-5600 4450);
FORCEPROP 1 LAST HDL_TAP TRUE
J 0
(-5275 4375);
DISPLAY 1.595745 (-5275 4375);
PAINT GREEN (-5275 4375);
DISPLAY INVISIBLE (-5275 4375);
FORCEADD TAP..6
(-5600 4550);
FORCEPROP 3 LASTPIN (-5550 4550) SIG_NAME M_A_DQ<60>
J 0
(-5540 4560);
DISPLAY 0.659574 (-5540 4560);
PAINT MONO (-5540 4560);
DISPLAY INVISIBLE (-5540 4560);
FORCEPROP 1 LASTPIN (-5550 4550) BN 60
J 0
(-5602 4558);
DISPLAY 0.617021 (-5602 4558);
PAINT PINK (-5602 4558);
FORCEPROP 2 LAST CDS_LIB mstr_standard
J 0
(-5600 4550);
PAINT MONO (-5600 4550);
DISPLAY INVISIBLE (-5600 4550);
FORCEPROP 1 LAST PATH I83
J 0
(-5602 4550);
DISPLAY 0.872340 (-5602 4550);
PAINT GREEN (-5602 4550);
DISPLAY INVISIBLE (-5602 4550);
FORCEPROP 1 LAST BODY_TYPE PLUMBING
J 0
(-5600 4500);
DISPLAY 1.595745 (-5600 4500);
PAINT GREEN (-5600 4500);
DISPLAY INVISIBLE (-5600 4500);
FORCEPROP 1 LAST HDL_TAP TRUE
J 0
(-5275 4425);
DISPLAY 1.595745 (-5275 4425);
PAINT GREEN (-5275 4425);
DISPLAY INVISIBLE (-5275 4425);
FORCEADD TAP..6
(-5600 4600);
FORCEPROP 3 LASTPIN (-5550 4600) SIG_NAME M_A_DQ<61>
J 0
(-5540 4610);
DISPLAY 0.659574 (-5540 4610);
PAINT MONO (-5540 4610);
DISPLAY INVISIBLE (-5540 4610);
FORCEPROP 1 LASTPIN (-5550 4600) BN 61
J 0
(-5602 4608);
DISPLAY 0.617021 (-5602 4608);
PAINT PINK (-5602 4608);
FORCEPROP 2 LAST CDS_LIB mstr_standard
J 0
(-5600 4600);
PAINT MONO (-5600 4600);
DISPLAY INVISIBLE (-5600 4600);
FORCEPROP 1 LAST PATH I84
J 0
(-5602 4600);
DISPLAY 0.872340 (-5602 4600);
PAINT GREEN (-5602 4600);
DISPLAY INVISIBLE (-5602 4600);
FORCEPROP 1 LAST BODY_TYPE PLUMBING
J 0
(-5600 4550);
DISPLAY 1.595745 (-5600 4550);
PAINT GREEN (-5600 4550);
DISPLAY INVISIBLE (-5600 4550);
FORCEPROP 1 LAST HDL_TAP TRUE
J 0
(-5275 4475);
DISPLAY 1.595745 (-5275 4475);
PAINT GREEN (-5275 4475);
DISPLAY INVISIBLE (-5275 4475);
FORCEADD TAP..6
(-5600 4650);
FORCEPROP 3 LASTPIN (-5550 4650) SIG_NAME M_A_DQ<62>
J 0
(-5540 4660);
DISPLAY 0.659574 (-5540 4660);
PAINT MONO (-5540 4660);
DISPLAY INVISIBLE (-5540 4660);
FORCEPROP 1 LASTPIN (-5550 4650) BN 62
J 0
(-5602 4658);
DISPLAY 0.617021 (-5602 4658);
PAINT PINK (-5602 4658);
FORCEPROP 2 LAST CDS_LIB mstr_standard
J 0
(-5600 4650);
PAINT MONO (-5600 4650);
DISPLAY INVISIBLE (-5600 4650);
FORCEPROP 1 LAST PATH I85
J 0
(-5602 4650);
DISPLAY 0.872340 (-5602 4650);
PAINT GREEN (-5602 4650);
DISPLAY INVISIBLE (-5602 4650);
FORCEPROP 1 LAST BODY_TYPE PLUMBING
J 0
(-5600 4600);
DISPLAY 1.595745 (-5600 4600);
PAINT GREEN (-5600 4600);
DISPLAY INVISIBLE (-5600 4600);
FORCEPROP 1 LAST HDL_TAP TRUE
J 0
(-5275 4525);
DISPLAY 1.595745 (-5275 4525);
PAINT GREEN (-5275 4525);
DISPLAY INVISIBLE (-5275 4525);
FORCEADD TAP..6
(-5600 4700);
FORCEPROP 3 LASTPIN (-5550 4700) SIG_NAME M_A_DQ<63>
J 0
(-5540 4710);
DISPLAY 0.659574 (-5540 4710);
PAINT MONO (-5540 4710);
DISPLAY INVISIBLE (-5540 4710);
FORCEPROP 1 LASTPIN (-5550 4700) BN 63
J 0
(-5602 4708);
DISPLAY 0.617021 (-5602 4708);
PAINT PINK (-5602 4708);
FORCEPROP 2 LAST CDS_LIB mstr_standard
J 0
(-5600 4700);
PAINT MONO (-5600 4700);
DISPLAY INVISIBLE (-5600 4700);
FORCEPROP 1 LAST PATH I86
J 0
(-5602 4700);
DISPLAY 0.872340 (-5602 4700);
PAINT GREEN (-5602 4700);
DISPLAY INVISIBLE (-5602 4700);
FORCEPROP 1 LAST BODY_TYPE PLUMBING
J 0
(-5600 4650);
DISPLAY 1.595745 (-5600 4650);
PAINT GREEN (-5600 4650);
DISPLAY INVISIBLE (-5600 4650);
FORCEPROP 1 LAST HDL_TAP TRUE
J 0
(-5275 4575);
DISPLAY 1.595745 (-5275 4575);
PAINT GREEN (-5275 4575);
DISPLAY INVISIBLE (-5275 4575);
FORCEADD TAP..6
R 2
(-2875 800);
FORCEPROP 3 LASTPIN (-2925 800) SIG_NAME M_A_BA<1>
J 0
(-2915 810);
DISPLAY 0.659574 (-2915 810);
PAINT MONO (-2915 810);
DISPLAY INVISIBLE (-2915 810);
FORCEPROP 1 LASTPIN (-2925 800) BN 1
J 2
(-2873 808);
DISPLAY 0.617021 (-2873 808);
PAINT PINK (-2873 808);
FORCEPROP 2 LAST CDS_LIB mstr_standard
J 0
(-2875 800);
PAINT MONO (-2875 800);
DISPLAY INVISIBLE (-2875 800);
FORCEPROP 1 LAST PATH I87
J 2
(-2873 800);
DISPLAY 0.872340 (-2873 800);
PAINT GREEN (-2873 800);
DISPLAY INVISIBLE (-2873 800);
FORCEPROP 1 LAST BODY_TYPE PLUMBING
J 2
(-2875 750);
DISPLAY 1.595745 (-2875 750);
PAINT GREEN (-2875 750);
DISPLAY INVISIBLE (-2875 750);
FORCEPROP 1 LAST HDL_TAP TRUE
J 2
(-3200 675);
DISPLAY 1.595745 (-3200 675);
PAINT GREEN (-3200 675);
DISPLAY INVISIBLE (-3200 675);
FORCEADD TAP..6
R 2
(-2875 750);
FORCEPROP 3 LASTPIN (-2925 750) SIG_NAME M_A_BA<0>
J 0
(-2915 760);
DISPLAY 0.659574 (-2915 760);
PAINT MONO (-2915 760);
DISPLAY INVISIBLE (-2915 760);
FORCEPROP 1 LASTPIN (-2925 750) BN 0
J 2
(-2873 758);
DISPLAY 0.617021 (-2873 758);
PAINT PINK (-2873 758);
FORCEPROP 2 LAST CDS_LIB mstr_standard
J 0
(-2875 750);
PAINT MONO (-2875 750);
DISPLAY INVISIBLE (-2875 750);
FORCEPROP 1 LAST PATH I88
J 2
(-2873 750);
DISPLAY 0.872340 (-2873 750);
PAINT GREEN (-2873 750);
DISPLAY INVISIBLE (-2873 750);
FORCEPROP 1 LAST BODY_TYPE PLUMBING
J 2
(-2875 700);
DISPLAY 1.595745 (-2875 700);
PAINT GREEN (-2875 700);
DISPLAY INVISIBLE (-2875 700);
FORCEPROP 1 LAST HDL_TAP TRUE
J 2
(-3200 625);
DISPLAY 1.595745 (-3200 625);
PAINT GREEN (-3200 625);
DISPLAY INVISIBLE (-3200 625);
FORCEADD TAP..6
R 2
(-2875 900);
FORCEPROP 3 LASTPIN (-2925 900) SIG_NAME M_A_BG<1>
J 0
(-2915 910);
DISPLAY 0.659574 (-2915 910);
PAINT MONO (-2915 910);
DISPLAY INVISIBLE (-2915 910);
FORCEPROP 1 LASTPIN (-2925 900) BN 1
J 2
(-2873 908);
DISPLAY 0.617021 (-2873 908);
PAINT PINK (-2873 908);
FORCEPROP 2 LAST CDS_LIB mstr_standard
J 0
(-2875 900);
PAINT MONO (-2875 900);
DISPLAY INVISIBLE (-2875 900);
FORCEPROP 1 LAST PATH I89
J 2
(-2873 900);
DISPLAY 0.872340 (-2873 900);
PAINT GREEN (-2873 900);
DISPLAY INVISIBLE (-2873 900);
FORCEPROP 1 LAST BODY_TYPE PLUMBING
J 2
(-2875 850);
DISPLAY 1.595745 (-2875 850);
PAINT GREEN (-2875 850);
DISPLAY INVISIBLE (-2875 850);
FORCEPROP 1 LAST HDL_TAP TRUE
J 2
(-3200 775);
DISPLAY 1.595745 (-3200 775);
PAINT GREEN (-3200 775);
DISPLAY INVISIBLE (-3200 775);
FORCEADD TAP..6
(-5600 900);
FORCEPROP 3 LASTPIN (-5550 900) SIG_NAME M_A_CLK_DP<1>
J 0
(-5540 910);
DISPLAY 0.659574 (-5540 910);
PAINT MONO (-5540 910);
DISPLAY INVISIBLE (-5540 910);
FORCEPROP 1 LASTPIN (-5550 900) BN 1
J 0
(-5602 908);
DISPLAY 0.617021 (-5602 908);
PAINT PINK (-5602 908);
FORCEPROP 2 LAST CDS_LIB mstr_standard
J 0
(-5600 900);
PAINT MONO (-5600 900);
DISPLAY INVISIBLE (-5600 900);
FORCEPROP 1 LAST PATH I9
J 0
(-5602 900);
DISPLAY 0.872340 (-5602 900);
PAINT GREEN (-5602 900);
DISPLAY INVISIBLE (-5602 900);
FORCEPROP 1 LAST BODY_TYPE PLUMBING
J 0
(-5600 850);
DISPLAY 1.595745 (-5600 850);
PAINT GREEN (-5600 850);
DISPLAY INVISIBLE (-5600 850);
FORCEPROP 1 LAST HDL_TAP TRUE
J 0
(-5275 775);
DISPLAY 1.595745 (-5275 775);
PAINT GREEN (-5275 775);
DISPLAY INVISIBLE (-5275 775);
FORCEADD TAP..6
R 2
(-2875 850);
FORCEPROP 3 LASTPIN (-2925 850) SIG_NAME M_A_BG<0>
J 0
(-2915 860);
DISPLAY 0.659574 (-2915 860);
PAINT MONO (-2915 860);
DISPLAY INVISIBLE (-2915 860);
FORCEPROP 1 LASTPIN (-2925 850) BN 0
J 2
(-2873 858);
DISPLAY 0.617021 (-2873 858);
PAINT PINK (-2873 858);
FORCEPROP 2 LAST CDS_LIB mstr_standard
J 0
(-2875 850);
PAINT MONO (-2875 850);
DISPLAY INVISIBLE (-2875 850);
FORCEPROP 1 LAST PATH I90
J 2
(-2873 850);
DISPLAY 0.872340 (-2873 850);
PAINT GREEN (-2873 850);
DISPLAY INVISIBLE (-2873 850);
FORCEPROP 1 LAST BODY_TYPE PLUMBING
J 2
(-2875 800);
DISPLAY 1.595745 (-2875 800);
PAINT GREEN (-2875 800);
DISPLAY INVISIBLE (-2875 800);
FORCEPROP 1 LAST HDL_TAP TRUE
J 2
(-3200 725);
DISPLAY 1.595745 (-3200 725);
PAINT GREEN (-3200 725);
DISPLAY INVISIBLE (-3200 725);
FORCEADD TAP..6
R 2
(-2875 1150);
FORCEPROP 3 LASTPIN (-2925 1150) SIG_NAME M_A_CS_N<3>
J 0
(-2915 1160);
DISPLAY 0.659574 (-2915 1160);
PAINT MONO (-2915 1160);
DISPLAY INVISIBLE (-2915 1160);
FORCEPROP 1 LASTPIN (-2925 1150) BN 3
J 2
(-2873 1158);
DISPLAY 0.617021 (-2873 1158);
PAINT PINK (-2873 1158);
FORCEPROP 2 LAST CDS_LIB mstr_standard
J 0
(-2875 1150);
PAINT MONO (-2875 1150);
DISPLAY INVISIBLE (-2875 1150);
FORCEPROP 1 LAST PATH I91
J 2
(-2873 1150);
DISPLAY 0.872340 (-2873 1150);
PAINT GREEN (-2873 1150);
DISPLAY INVISIBLE (-2873 1150);
FORCEPROP 1 LAST BODY_TYPE PLUMBING
J 2
(-2875 1100);
DISPLAY 1.595745 (-2875 1100);
PAINT GREEN (-2875 1100);
DISPLAY INVISIBLE (-2875 1100);
FORCEPROP 1 LAST HDL_TAP TRUE
J 2
(-3200 1025);
DISPLAY 1.595745 (-3200 1025);
PAINT GREEN (-3200 1025);
DISPLAY INVISIBLE (-3200 1025);
FORCEADD TAP..6
R 2
(-2875 1200);
FORCEPROP 3 LASTPIN (-2925 1200) SIG_NAME M_A_CS_N<4>
J 0
(-2915 1210);
DISPLAY 0.659574 (-2915 1210);
PAINT MONO (-2915 1210);
DISPLAY INVISIBLE (-2915 1210);
FORCEPROP 1 LASTPIN (-2925 1200) BN 4
J 2
(-2873 1208);
DISPLAY 0.617021 (-2873 1208);
PAINT PINK (-2873 1208);
FORCEPROP 2 LAST CDS_LIB mstr_standard
J 0
(-2875 1200);
PAINT MONO (-2875 1200);
DISPLAY INVISIBLE (-2875 1200);
FORCEPROP 1 LAST PATH I92
J 2
(-2873 1200);
DISPLAY 0.872340 (-2873 1200);
PAINT GREEN (-2873 1200);
DISPLAY INVISIBLE (-2873 1200);
FORCEPROP 1 LAST BODY_TYPE PLUMBING
J 2
(-2875 1150);
DISPLAY 1.595745 (-2875 1150);
PAINT GREEN (-2875 1150);
DISPLAY INVISIBLE (-2875 1150);
FORCEPROP 1 LAST HDL_TAP TRUE
J 2
(-3200 1075);
DISPLAY 1.595745 (-3200 1075);
PAINT GREEN (-3200 1075);
DISPLAY INVISIBLE (-3200 1075);
FORCEADD TAP..6
R 2
(-2875 1100);
FORCEPROP 3 LASTPIN (-2925 1100) SIG_NAME M_A_CS_N<2>
J 0
(-2915 1110);
DISPLAY 0.659574 (-2915 1110);
PAINT MONO (-2915 1110);
DISPLAY INVISIBLE (-2915 1110);
FORCEPROP 1 LASTPIN (-2925 1100) BN 2
J 2
(-2873 1108);
DISPLAY 0.617021 (-2873 1108);
PAINT PINK (-2873 1108);
FORCEPROP 2 LAST CDS_LIB mstr_standard
J 0
(-2875 1100);
PAINT MONO (-2875 1100);
DISPLAY INVISIBLE (-2875 1100);
FORCEPROP 1 LAST PATH I93
J 2
(-2873 1100);
DISPLAY 0.872340 (-2873 1100);
PAINT GREEN (-2873 1100);
DISPLAY INVISIBLE (-2873 1100);
FORCEPROP 1 LAST BODY_TYPE PLUMBING
J 2
(-2875 1050);
DISPLAY 1.595745 (-2875 1050);
PAINT GREEN (-2875 1050);
DISPLAY INVISIBLE (-2875 1050);
FORCEPROP 1 LAST HDL_TAP TRUE
J 2
(-3200 975);
DISPLAY 1.595745 (-3200 975);
PAINT GREEN (-3200 975);
DISPLAY INVISIBLE (-3200 975);
FORCEADD TAP..6
R 2
(-2875 1050);
FORCEPROP 3 LASTPIN (-2925 1050) SIG_NAME M_A_CS_N<1>
J 0
(-2915 1060);
DISPLAY 0.659574 (-2915 1060);
PAINT MONO (-2915 1060);
DISPLAY INVISIBLE (-2915 1060);
FORCEPROP 1 LASTPIN (-2925 1050) BN 1
J 2
(-2873 1058);
DISPLAY 0.617021 (-2873 1058);
PAINT PINK (-2873 1058);
FORCEPROP 2 LAST CDS_LIB mstr_standard
J 0
(-2875 1050);
PAINT MONO (-2875 1050);
DISPLAY INVISIBLE (-2875 1050);
FORCEPROP 1 LAST PATH I94
J 2
(-2873 1050);
DISPLAY 0.872340 (-2873 1050);
PAINT GREEN (-2873 1050);
DISPLAY INVISIBLE (-2873 1050);
FORCEPROP 1 LAST BODY_TYPE PLUMBING
J 2
(-2875 1000);
DISPLAY 1.595745 (-2875 1000);
PAINT GREEN (-2875 1000);
DISPLAY INVISIBLE (-2875 1000);
FORCEPROP 1 LAST HDL_TAP TRUE
J 2
(-3200 925);
DISPLAY 1.595745 (-3200 925);
PAINT GREEN (-3200 925);
DISPLAY INVISIBLE (-3200 925);
FORCEADD TAP..6
R 2
(-2875 1000);
FORCEPROP 3 LASTPIN (-2925 1000) SIG_NAME M_A_CS_N<0>
J 0
(-2915 1010);
DISPLAY 0.659574 (-2915 1010);
PAINT MONO (-2915 1010);
DISPLAY INVISIBLE (-2915 1010);
FORCEPROP 1 LASTPIN (-2925 1000) BN 0
J 2
(-2873 1008);
DISPLAY 0.617021 (-2873 1008);
PAINT PINK (-2873 1008);
FORCEPROP 2 LAST CDS_LIB mstr_standard
J 0
(-2875 1000);
PAINT MONO (-2875 1000);
DISPLAY INVISIBLE (-2875 1000);
FORCEPROP 1 LAST PATH I95
J 2
(-2873 1000);
DISPLAY 0.872340 (-2873 1000);
PAINT GREEN (-2873 1000);
DISPLAY INVISIBLE (-2873 1000);
FORCEPROP 1 LAST BODY_TYPE PLUMBING
J 2
(-2875 950);
DISPLAY 1.595745 (-2875 950);
PAINT GREEN (-2875 950);
DISPLAY INVISIBLE (-2875 950);
FORCEPROP 1 LAST HDL_TAP TRUE
J 2
(-3200 875);
DISPLAY 1.595745 (-3200 875);
PAINT GREEN (-3200 875);
DISPLAY INVISIBLE (-3200 875);
FORCEADD TAP..6
R 2
(-2875 1300);
FORCEPROP 3 LASTPIN (-2925 1300) SIG_NAME M_A_CS_N<6>
J 0
(-2915 1310);
DISPLAY 0.659574 (-2915 1310);
PAINT MONO (-2915 1310);
DISPLAY INVISIBLE (-2915 1310);
FORCEPROP 1 LASTPIN (-2925 1300) BN 6
J 2
(-2873 1308);
DISPLAY 0.617021 (-2873 1308);
PAINT PINK (-2873 1308);
FORCEPROP 2 LAST CDS_LIB mstr_standard
J 0
(-2875 1300);
PAINT MONO (-2875 1300);
DISPLAY INVISIBLE (-2875 1300);
FORCEPROP 1 LAST PATH I96
J 2
(-2873 1300);
DISPLAY 0.872340 (-2873 1300);
PAINT GREEN (-2873 1300);
DISPLAY INVISIBLE (-2873 1300);
FORCEPROP 1 LAST BODY_TYPE PLUMBING
J 2
(-2875 1250);
DISPLAY 1.595745 (-2875 1250);
PAINT GREEN (-2875 1250);
DISPLAY INVISIBLE (-2875 1250);
FORCEPROP 1 LAST HDL_TAP TRUE
J 2
(-3200 1175);
DISPLAY 1.595745 (-3200 1175);
PAINT GREEN (-3200 1175);
DISPLAY INVISIBLE (-3200 1175);
FORCEADD TAP..6
R 2
(-2875 1350);
FORCEPROP 3 LASTPIN (-2925 1350) SIG_NAME M_A_CS_N<7>
J 0
(-2915 1360);
DISPLAY 0.659574 (-2915 1360);
PAINT MONO (-2915 1360);
DISPLAY INVISIBLE (-2915 1360);
FORCEPROP 1 LASTPIN (-2925 1350) BN 7
J 2
(-2873 1358);
DISPLAY 0.617021 (-2873 1358);
PAINT PINK (-2873 1358);
FORCEPROP 2 LAST CDS_LIB mstr_standard
J 0
(-2875 1350);
PAINT MONO (-2875 1350);
DISPLAY INVISIBLE (-2875 1350);
FORCEPROP 1 LAST PATH I97
J 2
(-2873 1350);
DISPLAY 0.872340 (-2873 1350);
PAINT GREEN (-2873 1350);
DISPLAY INVISIBLE (-2873 1350);
FORCEPROP 1 LAST BODY_TYPE PLUMBING
J 2
(-2875 1300);
DISPLAY 1.595745 (-2875 1300);
PAINT GREEN (-2875 1300);
DISPLAY INVISIBLE (-2875 1300);
FORCEPROP 1 LAST HDL_TAP TRUE
J 2
(-3200 1225);
DISPLAY 1.595745 (-3200 1225);
PAINT GREEN (-3200 1225);
DISPLAY INVISIBLE (-3200 1225);
FORCEADD TAP..6
R 2
(-2875 1250);
FORCEPROP 3 LASTPIN (-2925 1250) SIG_NAME M_A_CS_N<5>
J 0
(-2915 1260);
DISPLAY 0.659574 (-2915 1260);
PAINT MONO (-2915 1260);
DISPLAY INVISIBLE (-2915 1260);
FORCEPROP 1 LASTPIN (-2925 1250) BN 5
J 2
(-2873 1258);
DISPLAY 0.617021 (-2873 1258);
PAINT PINK (-2873 1258);
FORCEPROP 2 LAST CDS_LIB mstr_standard
J 0
(-2875 1250);
PAINT MONO (-2875 1250);
DISPLAY INVISIBLE (-2875 1250);
FORCEPROP 1 LAST PATH I98
J 2
(-2873 1250);
DISPLAY 0.872340 (-2873 1250);
PAINT GREEN (-2873 1250);
DISPLAY INVISIBLE (-2873 1250);
FORCEPROP 1 LAST BODY_TYPE PLUMBING
J 2
(-2875 1200);
DISPLAY 1.595745 (-2875 1200);
PAINT GREEN (-2875 1200);
DISPLAY INVISIBLE (-2875 1200);
FORCEPROP 1 LAST HDL_TAP TRUE
J 2
(-3200 1125);
DISPLAY 1.595745 (-3200 1125);
PAINT GREEN (-3200 1125);
DISPLAY INVISIBLE (-3200 1125);
FORCEADD TAP..6
R 2
(-2875 1450);
FORCEPROP 3 LASTPIN (-2925 1450) SIG_NAME M_A_ODT<0>
J 0
(-2915 1460);
DISPLAY 0.659574 (-2915 1460);
PAINT MONO (-2915 1460);
DISPLAY INVISIBLE (-2915 1460);
FORCEPROP 1 LASTPIN (-2925 1450) BN 0
J 2
(-2873 1458);
DISPLAY 0.617021 (-2873 1458);
PAINT PINK (-2873 1458);
FORCEPROP 2 LAST CDS_LIB mstr_standard
J 0
(-2875 1450);
PAINT MONO (-2875 1450);
DISPLAY INVISIBLE (-2875 1450);
FORCEPROP 1 LAST PATH I99
J 2
(-2873 1450);
DISPLAY 0.872340 (-2873 1450);
PAINT GREEN (-2873 1450);
DISPLAY INVISIBLE (-2873 1450);
FORCEPROP 1 LAST BODY_TYPE PLUMBING
J 2
(-2875 1400);
DISPLAY 1.595745 (-2875 1400);
PAINT GREEN (-2875 1400);
DISPLAY INVISIBLE (-2875 1400);
FORCEPROP 1 LAST HDL_TAP TRUE
J 2
(-3200 1325);
DISPLAY 1.595745 (-3200 1325);
PAINT GREEN (-3200 1325);
DISPLAY INVISIBLE (-3200 1325);
FORCEADD DESIGN_NOTE..1
(-6300 425);
FORCEPROP 0 LAST L1 CPU SYMBOLS 1-30 ARE PRELIMINARY AND SUBJECT TO CHANGE
J 0
(-6500 300);
DISPLAY 1.021277 (-6500 300);
PAINT ORANGE (-6500 300);
FORCEPROP 2 LAST CDS_LIB mstr_symbols
J 0
(-6300 425);
PAINT ORANGE (-6300 425);
DISPLAY INVISIBLE (-6300 425);
FORCEPROP 1 LAST COMMENT_BODY TRUE
J 0
(-6275 525);
DISPLAY 0.978723 (-6275 525);
PAINT ORANGE (-6275 525);
DISPLAY INVISIBLE (-6275 525);
FORCEADD INTEL_CORP_BPAGE..1
(0 0);
FORCEPROP 1 LAST CDS_CON_LAST_MODIFIED Fri Jun 16 17:48:09 2017
J 0
(-1425 325);
DISPLAY 1.340426 (-1425 325);
PAINT GREEN (-1425 325);
DISPLAY INVISIBLE (-1425 325);
FORCEPROP 1 LAST CUSTOM_TXT_CDS <CURRENT_DESIGN_SHEET> OF <TOTAL_DESIGN_SHEETS>
J 0
(-500 25);
PAINT ORANGE (-500 25);
FORCEPROP 1 LAST CUSTOM_TXT_CDS <CON_LAST_MODIFIED>
J 0
(-4000 100);
PAINT ORANGE (-4000 100);
FORCEPROP 2 LAST CUSTOM_TXT_CDS <XR_PAGE_TITLE>
J 0
(-7890 5250);
DISPLAY 0.638298 (-7890 5250);
PAINT PINK (-7890 5250);
DISPLAY INVISIBLE (-7890 5250);
FORCEPROP 1 LAST SCH_TITLE SKYLAKE - SKT0 - 3 OF 21
J 0
(-7950 50);
DISPLAY 1.212766 (-7950 50);
PAINT GREEN (-7950 50);
FORCEPROP 2 LAST CDS_LIB mstr_symbols
J 0
(0 0);
PAINT ORANGE (0 0);
DISPLAY INVISIBLE (0 0);
FORCEPROP 2 LAST PAGE_BORDER TRUE
J 0
(-7890 5250);
DISPLAY 0.851064 (-7890 5250);
PAINT PINK (-7890 5250);
DISPLAY INVISIBLE (-7890 5250);
FORCEPROP 1 LAST COMMENT_BODY TRUE
J 0
(12 12);
DISPLAY 0.638298 (12 12);
PAINT GREEN (12 12);
DISPLAY INVISIBLE (12 12);
FORCEPROP 2 LAST CDS_XR_PAGE_TITLE CR-23 : @BASEBOARD_FAB2_LIB.BASEBOARD_FAB2(SCH_1):PAGE23
J 0
(-7890 5250);
DISPLAY 0.638298 (-7890 5250);
PAINT PINK (-7890 5250);
DISPLAY INVISIBLE (-7890 5250);
FORCEADD PRELIM..10
(-4240 2590);
PAINT GRAY (-4240 2590);
FORCEPROP 2 LAST CDS_LIB mstr_misc
J 0
(-4240 2590);
PAINT ORANGE (-4240 2590);
DISPLAY INVISIBLE (-4240 2590);
FORCEPROP 1 LAST COMMENT_BODY TRUE
J 0
(-4240 2590);
PAINT ORANGE (-4240 2590);
DISPLAY INVISIBLE (-4240 2590);
WIRE 17 -1 (-5650 4825)(-6400 4825);
FORCEPROP 2 LAST SIG_NAME M_A_DQ<63:0>
J 0
(-6350 4835);
DISPLAY 0.617021 (-6350 4835);
PAINT ORANGE (-6350 4835);
WIRE 17 -1 (-5650 4725)(-5650 4825);
WIRE 17 -1 (-5650 4675)(-5650 4725);
WIRE 17 -1 (-5650 4625)(-5650 4675);
WIRE 17 -1 (-5650 4575)(-5650 4625);
WIRE 17 -1 (-5650 4525)(-5650 4575);
WIRE 17 -1 (-5650 4475)(-5650 4525);
WIRE 17 -1 (-5650 4425)(-5650 4475);
WIRE 17 -1 (-5650 4375)(-5650 4425);
WIRE 17 -1 (-5650 4325)(-5650 4375);
WIRE 17 -1 (-5650 4275)(-5650 4325);
WIRE 17 -1 (-5650 4225)(-5650 4275);
WIRE 17 -1 (-5650 4175)(-5650 4225);
WIRE 17 -1 (-5650 4125)(-5650 4175);
WIRE 17 -1 (-5650 4075)(-5650 4125);
WIRE 17 -1 (-5650 4025)(-5650 4075);
WIRE 17 -1 (-5650 3975)(-5650 4025);
WIRE 17 -1 (-5650 3925)(-5650 3975);
WIRE 17 -1 (-5650 3875)(-5650 3925);
WIRE 17 -1 (-5650 3825)(-5650 3875);
WIRE 17 -1 (-5650 3775)(-5650 3825);
WIRE 17 -1 (-5650 3725)(-5650 3775);
WIRE 17 -1 (-5650 3675)(-5650 3725);
WIRE 17 -1 (-5650 3625)(-5650 3675);
WIRE 17 -1 (-5650 3575)(-5650 3625);
WIRE 17 -1 (-5650 3525)(-5650 3575);
WIRE 17 -1 (-5650 3475)(-5650 3525);
WIRE 17 -1 (-5650 3425)(-5650 3475);
WIRE 17 -1 (-5650 3375)(-5650 3425);
WIRE 17 -1 (-5650 3325)(-5650 3375);
WIRE 17 -1 (-5650 3275)(-5650 3325);
WIRE 17 -1 (-5650 3225)(-5650 3275);
WIRE 17 -1 (-5650 3175)(-5650 3225);
WIRE 17 -1 (-5650 3125)(-5650 3175);
WIRE 17 -1 (-5650 3075)(-5650 3125);
WIRE 17 -1 (-5650 3025)(-5650 3075);
WIRE 17 -1 (-5650 2975)(-5650 3025);
WIRE 17 -1 (-5650 2925)(-5650 2975);
WIRE 17 -1 (-5650 2875)(-5650 2925);
WIRE 17 -1 (-5650 2825)(-5650 2875);
WIRE 17 -1 (-5650 2775)(-5650 2825);
WIRE 17 -1 (-5650 2725)(-5650 2775);
WIRE 17 -1 (-5650 2675)(-5650 2725);
WIRE 17 -1 (-5650 2625)(-5650 2675);
WIRE 17 -1 (-5650 2575)(-5650 2625);
WIRE 17 -1 (-5650 2525)(-5650 2575);
WIRE 17 -1 (-5650 2475)(-5650 2525);
WIRE 17 -1 (-5650 2425)(-5650 2475);
WIRE 17 -1 (-5650 2375)(-5650 2425);
WIRE 17 -1 (-5650 2325)(-5650 2375);
WIRE 17 -1 (-5650 2275)(-5650 2325);
WIRE 17 -1 (-5650 2225)(-5650 2275);
WIRE 17 -1 (-5650 2175)(-5650 2225);
WIRE 17 -1 (-5650 2125)(-5650 2175);
WIRE 17 -1 (-5650 2075)(-5650 2125);
WIRE 17 -1 (-5650 2025)(-5650 2075);
WIRE 17 -1 (-5650 1575)(-5650 1625);
WIRE 17 -1 (-5650 1975)(-5650 2025);
WIRE 17 -1 (-5650 1925)(-5650 1975);
WIRE 17 -1 (-5650 1625)(-5650 1675);
WIRE 17 -1 (-5650 1675)(-5650 1725);
WIRE 17 -1 (-5650 1875)(-5650 1925);
WIRE 17 -1 (-5650 1825)(-5650 1875);
WIRE 17 -1 (-5650 1725)(-5650 1775);
WIRE 17 -1 (-5650 1775)(-5650 1825);
WIRE 17 -1 (-5650 1500)(-6400 1500);
FORCEPROP 2 LAST SIG_NAME M_A_ECC<7:0>
J 0
(-6350 1510);
DISPLAY 0.617021 (-6350 1510);
PAINT ORANGE (-6350 1510);
WIRE 17 -1 (-5650 1475)(-5650 1500);
WIRE 17 -1 (-5650 1425)(-5650 1475);
WIRE 17 -1 (-5650 1375)(-5650 1425);
WIRE 17 -1 (-5650 1325)(-5650 1375);
WIRE 17 -1 (-5650 1275)(-5650 1325);
WIRE 17 -1 (-5650 1225)(-5650 1275);
WIRE 17 -1 (-5650 1175)(-5650 1225);
WIRE 17 -1 (-5650 1125)(-5650 1175);
WIRE 17 -1 (-5650 1050)(-6400 1050);
FORCEPROP 2 LAST SIG_NAME M_A_CLK_DP<3:0>
J 0
(-6350 1060);
DISPLAY 0.617021 (-6350 1060);
PAINT ORANGE (-6350 1060);
WIRE 17 -1 (-5650 1025)(-5650 1050);
WIRE 17 -1 (-5650 975)(-5650 1025);
WIRE 17 -1 (-5650 925)(-5650 975);
WIRE 17 -1 (-5650 875)(-5650 925);
WIRE 17 -1 (-5650 850)(-6400 850);
FORCEPROP 2 LAST SIG_NAME M_A_CLK_DN<3:0>
J 0
(-6350 860);
DISPLAY 0.617021 (-6350 860);
PAINT ORANGE (-6350 860);
WIRE 17 -1 (-5650 825)(-5650 850);
WIRE 17 -1 (-5650 775)(-5650 825);
WIRE 17 -1 (-5650 725)(-5650 775);
WIRE 17 -1 (-5650 675)(-5650 725);
WIRE 17 -1 (-2075 1650)(-2825 1650);
FORCEPROP 2 LAST SIG_NAME M_A_ODT<3:0>
J 0
(-2725 1660);
DISPLAY 0.617021 (-2725 1660);
PAINT ORANGE (-2725 1660);
WIRE 17 -1 (-2825 1625)(-2825 1650);
WIRE 17 -1 (-2825 1575)(-2825 1625);
WIRE 17 -1 (-2825 1525)(-2825 1575);
WIRE 17 -1 (-2825 1475)(-2825 1525);
WIRE 17 -1 (-2075 2850)(-2825 2850);
FORCEPROP 2 LAST SIG_NAME M_A_MA<17:0>
J 0
(-2725 2860);
DISPLAY 0.617021 (-2725 2860);
PAINT ORANGE (-2725 2860);
WIRE 17 -1 (-2825 2825)(-2825 2850);
WIRE 17 -1 (-2825 2775)(-2825 2825);
WIRE 17 -1 (-2825 2725)(-2825 2775);
WIRE 17 -1 (-2825 2675)(-2825 2725);
WIRE 17 -1 (-2825 2625)(-2825 2675);
WIRE 17 -1 (-2825 2575)(-2825 2625);
WIRE 17 -1 (-2825 2525)(-2825 2575);
WIRE 17 -1 (-2825 2475)(-2825 2525);
WIRE 17 -1 (-2825 2425)(-2825 2475);
WIRE 17 -1 (-2825 2375)(-2825 2425);
WIRE 17 -1 (-2825 2325)(-2825 2375);
WIRE 17 -1 (-2825 2275)(-2825 2325);
WIRE 17 -1 (-2825 2225)(-2825 2275);
WIRE 17 -1 (-2825 2175)(-2825 2225);
WIRE 17 -1 (-2825 2125)(-2825 2175);
WIRE 17 -1 (-2825 2075)(-2825 2125);
WIRE 17 -1 (-2825 2025)(-2825 2075);
WIRE 17 -1 (-2825 1975)(-2825 2025);
WIRE 17 -1 (-2075 1400)(-2825 1400);
FORCEPROP 2 LAST SIG_NAME M_A_CS_N<7:0>
J 0
(-2725 1410);
DISPLAY 0.617021 (-2725 1410);
PAINT ORANGE (-2725 1410);
WIRE 17 -1 (-2825 1375)(-2825 1400);
WIRE 17 -1 (-2825 1325)(-2825 1375);
WIRE 17 -1 (-2825 1275)(-2825 1325);
WIRE 17 -1 (-2825 1225)(-2825 1275);
WIRE 17 -1 (-2825 1175)(-2825 1225);
WIRE 17 -1 (-2825 1125)(-2825 1175);
WIRE 17 -1 (-2825 1075)(-2825 1125);
WIRE 17 -1 (-2825 1025)(-2825 1075);
WIRE 17 -1 (-2075 1900)(-2825 1900);
FORCEPROP 2 LAST SIG_NAME M_A_CKE<3:0>
J 0
(-2725 1910);
DISPLAY 0.617021 (-2725 1910);
PAINT ORANGE (-2725 1910);
WIRE 17 -1 (-2825 1875)(-2825 1900);
WIRE 17 -1 (-2825 1825)(-2825 1875);
WIRE 17 -1 (-2825 1775)(-2825 1825);
WIRE 17 -1 (-2825 1725)(-2825 1775);
WIRE 17 -1 (-2075 950)(-2825 950);
FORCEPROP 2 LAST SIG_NAME M_A_BG<1:0>
J 0
(-2725 960);
DISPLAY 0.617021 (-2725 960);
PAINT ORANGE (-2725 960);
WIRE 17 -1 (-2825 925)(-2825 950);
WIRE 17 -1 (-2825 875)(-2825 925);
WIRE 17 -1 (-2075 850)(-2825 850);
FORCEPROP 2 LAST SIG_NAME M_A_BA<1:0>
J 0
(-2725 860);
DISPLAY 0.617021 (-2725 860);
PAINT ORANGE (-2725 860);
WIRE 17 -1 (-2825 825)(-2825 850);
WIRE 17 -1 (-2825 775)(-2825 825);
WIRE 17 -1 (-2075 4775)(-2825 4775);
FORCEPROP 2 LAST SIG_NAME M_A_DQS_DP<17:0>
J 0
(-2725 4785);
DISPLAY 0.617021 (-2725 4785);
PAINT ORANGE (-2725 4785);
WIRE 17 -1 (-2825 4725)(-2825 4775);
WIRE 17 -1 (-2825 4675)(-2825 4725);
WIRE 17 -1 (-2825 4625)(-2825 4675);
WIRE 17 -1 (-2825 4575)(-2825 4625);
WIRE 17 -1 (-2825 4525)(-2825 4575);
WIRE 17 -1 (-2825 4475)(-2825 4525);
WIRE 17 -1 (-2825 4425)(-2825 4475);
WIRE 17 -1 (-2825 4375)(-2825 4425);
WIRE 17 -1 (-2825 4325)(-2825 4375);
WIRE 17 -1 (-2825 4275)(-2825 4325);
WIRE 17 -1 (-2825 4225)(-2825 4275);
WIRE 17 -1 (-2825 4175)(-2825 4225);
WIRE 17 -1 (-2825 4125)(-2825 4175);
WIRE 17 -1 (-2825 4075)(-2825 4125);
WIRE 17 -1 (-2825 4025)(-2825 4075);
WIRE 17 -1 (-2825 3975)(-2825 4025);
WIRE 17 -1 (-2825 3925)(-2825 3975);
WIRE 17 -1 (-2825 3875)(-2825 3925);
WIRE 17 -1 (-2075 3800)(-2825 3800);
FORCEPROP 2 LAST SIG_NAME M_A_DQS_DN<17:0>
J 0
(-2725 3810);
DISPLAY 0.617021 (-2725 3810);
PAINT ORANGE (-2725 3810);
WIRE 17 -1 (-2825 3775)(-2825 3800);
WIRE 17 -1 (-2825 3725)(-2825 3775);
WIRE 17 -1 (-2825 3675)(-2825 3725);
WIRE 17 -1 (-2825 3625)(-2825 3675);
WIRE 17 -1 (-2825 3575)(-2825 3625);
WIRE 17 -1 (-2825 3525)(-2825 3575);
WIRE 17 -1 (-2825 3475)(-2825 3525);
WIRE 17 -1 (-2825 3425)(-2825 3475);
WIRE 17 -1 (-2825 3375)(-2825 3425);
WIRE 17 -1 (-2825 3325)(-2825 3375);
WIRE 17 -1 (-2825 3275)(-2825 3325);
WIRE 17 -1 (-2825 3225)(-2825 3275);
WIRE 17 -1 (-2825 3175)(-2825 3225);
WIRE 17 -1 (-2825 3125)(-2825 3175);
WIRE 17 -1 (-2825 3075)(-2825 3125);
WIRE 17 -1 (-2825 3025)(-2825 3075);
WIRE 17 -1 (-2825 2975)(-2825 3025);
WIRE 17 -1 (-2825 2925)(-2825 2975);
WIRE 16 -1 (-5050 4250)(-5550 4250);
WIRE 16 -1 (-5050 3550)(-5550 3550);
WIRE 16 -1 (-3350 3900)(-2925 3900);
WIRE 16 -1 (-5050 4150)(-5550 4150);
WIRE 16 -1 (-3350 1550)(-2925 1550);
WIRE 16 -1 (-5550 3250)(-5050 3250);
WIRE 16 -1 (-5550 3150)(-5050 3150);
WIRE 16 -1 (-5050 3400)(-5550 3400);
WIRE 16 -1 (-3350 4700)(-2925 4700);
WIRE 16 -1 (-3350 4650)(-2925 4650);
WIRE 16 -1 (-3350 4600)(-2925 4600);
WIRE 16 -1 (-3350 4550)(-2925 4550);
WIRE 16 -1 (-3350 4500)(-2925 4500);
WIRE 16 -1 (-3350 4450)(-2925 4450);
WIRE 16 -1 (-3350 4400)(-2925 4400);
WIRE 16 -1 (-3350 4350)(-2925 4350);
WIRE 16 -1 (-3350 4300)(-2925 4300);
WIRE 16 -1 (-3350 4250)(-2925 4250);
WIRE 16 -1 (-3350 4200)(-2925 4200);
WIRE 16 -1 (-3350 4150)(-2925 4150);
WIRE 16 -1 (-3350 4100)(-2925 4100);
WIRE 16 -1 (-3350 3750)(-2925 3750);
WIRE 16 -1 (-3350 3700)(-2925 3700);
WIRE 16 -1 (-3350 3650)(-2925 3650);
WIRE 16 -1 (-3350 3600)(-2925 3600);
WIRE 16 -1 (-3350 3550)(-2925 3550);
WIRE 16 -1 (-3350 3500)(-2925 3500);
WIRE 16 -1 (-3350 3450)(-2925 3450);
WIRE 16 -1 (-3350 3400)(-2925 3400);
WIRE 16 -1 (-3350 3350)(-2925 3350);
WIRE 16 -1 (-3350 3300)(-2925 3300);
WIRE 16 -1 (-3350 3250)(-2925 3250);
WIRE 16 -1 (-3350 3200)(-2925 3200);
WIRE 16 -1 (-3350 3150)(-2925 3150);
WIRE 16 -1 (-3350 3100)(-2925 3100);
WIRE 16 -1 (-3350 3050)(-2925 3050);
WIRE 16 -1 (-3350 3000)(-2925 3000);
WIRE 16 -1 (-3350 2950)(-2925 2950);
WIRE 16 -1 (-3350 2900)(-2925 2900);
WIRE 16 -1 (-3350 4050)(-2925 4050);
WIRE 16 -1 (-3350 4000)(-2925 4000);
WIRE 16 -1 (-3350 3950)(-2925 3950);
WIRE 16 -1 (-3350 3850)(-2925 3850);
WIRE 16 -1 (-3350 2800)(-2925 2800);
WIRE 16 -1 (-3350 2750)(-2925 2750);
WIRE 16 -1 (-3350 2700)(-2925 2700);
WIRE 16 -1 (-3350 2650)(-2925 2650);
WIRE 16 -1 (-3350 2600)(-2925 2600);
WIRE 16 -1 (-3350 2550)(-2925 2550);
WIRE 16 -1 (-3350 2500)(-2925 2500);
WIRE 16 -1 (-3350 2450)(-2925 2450);
WIRE 16 -1 (-3350 2400)(-2925 2400);
WIRE 16 -1 (-3350 2350)(-2925 2350);
WIRE 16 -1 (-3350 2300)(-2925 2300);
WIRE 16 -1 (-3350 2250)(-2925 2250);
WIRE 16 -1 (-3350 2200)(-2925 2200);
WIRE 16 -1 (-3350 2150)(-2925 2150);
WIRE 16 -1 (-3350 2100)(-2925 2100);
WIRE 16 -1 (-3350 2050)(-2925 2050);
WIRE 16 -1 (-2075 650)(-3350 650);
FORCEPROP 2 LAST SIG_NAME M_A_ACT_N
J 0
(-2725 660);
DISPLAY 0.617021 (-2725 660);
PAINT ORANGE (-2725 660);
WIRE 16 -1 (-2075 600)(-3350 600);
FORCEPROP 2 LAST SIG_NAME M_A_ALERT_N
J 0
(-2725 610);
DISPLAY 0.617021 (-2725 610);
PAINT ORANGE (-2725 610);
WIRE 16 -1 (-2075 550)(-3350 550);
FORCEPROP 2 LAST SIG_NAME M_A_PAR
J 0
(-2725 560);
DISPLAY 0.617021 (-2725 560);
PAINT ORANGE (-2725 560);
WIRE 16 -1 (-3350 800)(-2925 800);
WIRE 16 -1 (-3350 750)(-2925 750);
WIRE 16 -1 (-3350 900)(-2925 900);
WIRE 16 -1 (-3350 850)(-2925 850);
WIRE 16 -1 (-3350 1850)(-2925 1850);
WIRE 16 -1 (-3350 1800)(-2925 1800);
WIRE 16 -1 (-3350 1750)(-2925 1750);
WIRE 16 -1 (-3350 1700)(-2925 1700);
WIRE 16 -1 (-3350 1350)(-2925 1350);
WIRE 16 -1 (-3350 1300)(-2925 1300);
WIRE 16 -1 (-3350 1250)(-2925 1250);
WIRE 16 -1 (-3350 1200)(-2925 1200);
WIRE 16 -1 (-3350 1150)(-2925 1150);
WIRE 16 -1 (-3350 1100)(-2925 1100);
WIRE 16 -1 (-3350 1050)(-2925 1050);
WIRE 16 -1 (-3350 1000)(-2925 1000);
WIRE 16 -1 (-3350 2000)(-2925 2000);
WIRE 16 -1 (-3350 1950)(-2925 1950);
WIRE 16 -1 (-3350 1600)(-2925 1600);
WIRE 16 -1 (-3350 1500)(-2925 1500);
WIRE 16 -1 (-3350 1450)(-2925 1450);
WIRE 16 -1 (-5050 4700)(-5550 4700);
WIRE 16 -1 (-5050 4650)(-5550 4650);
WIRE 16 -1 (-5050 4600)(-5550 4600);
WIRE 16 -1 (-5050 4550)(-5550 4550);
WIRE 16 -1 (-5050 4500)(-5550 4500);
WIRE 16 -1 (-5050 4450)(-5550 4450);
WIRE 16 -1 (-5050 4400)(-5550 4400);
WIRE 16 -1 (-5050 4350)(-5550 4350);
WIRE 16 -1 (-5050 4300)(-5550 4300);
WIRE 16 -1 (-5050 4200)(-5550 4200);
WIRE 16 -1 (-5050 4100)(-5550 4100);
WIRE 16 -1 (-5050 4050)(-5550 4050);
WIRE 16 -1 (-5050 4000)(-5550 4000);
WIRE 16 -1 (-5050 3950)(-5550 3950);
WIRE 16 -1 (-5050 3900)(-5550 3900);
WIRE 16 -1 (-5050 3850)(-5550 3850);
WIRE 16 -1 (-5050 3800)(-5550 3800);
WIRE 16 -1 (-5050 3750)(-5550 3750);
WIRE 16 -1 (-5050 3700)(-5550 3700);
WIRE 16 -1 (-5550 3650)(-5050 3650);
WIRE 16 -1 (-5550 3600)(-5050 3600);
WIRE 16 -1 (-5550 3500)(-5050 3500);
WIRE 16 -1 (-5550 3450)(-5050 3450);
WIRE 16 -1 (-5550 3350)(-5050 3350);
WIRE 16 -1 (-5550 3300)(-5050 3300);
WIRE 16 -1 (-5550 3200)(-5050 3200);
WIRE 16 -1 (-5550 3100)(-5050 3100);
WIRE 16 -1 (-5050 3050)(-5550 3050);
WIRE 16 -1 (-5550 3000)(-5050 3000);
WIRE 16 -1 (-5550 2950)(-5050 2950);
WIRE 16 -1 (-5550 2900)(-5050 2900);
WIRE 16 -1 (-5550 2850)(-5050 2850);
WIRE 16 -1 (-5550 2800)(-5050 2800);
WIRE 16 -1 (-5550 2750)(-5050 2750);
WIRE 16 -1 (-5050 2700)(-5550 2700);
WIRE 16 -1 (-5550 2650)(-5050 2650);
WIRE 16 -1 (-5550 2600)(-5050 2600);
WIRE 16 -1 (-5550 2550)(-5050 2550);
WIRE 16 -1 (-5550 2500)(-5050 2500);
WIRE 16 -1 (-5050 2450)(-5550 2450);
WIRE 16 -1 (-5550 2400)(-5050 2400);
WIRE 16 -1 (-5550 2350)(-5050 2350);
WIRE 16 -1 (-5050 2300)(-5550 2300);
WIRE 16 -1 (-5550 2250)(-5050 2250);
WIRE 16 -1 (-5550 2200)(-5050 2200);
WIRE 16 -1 (-5550 2150)(-5050 2150);
WIRE 16 -1 (-5550 2100)(-5050 2100);
WIRE 16 -1 (-5550 2050)(-5050 2050);
WIRE 16 -1 (-5050 800)(-5550 800);
WIRE 16 -1 (-5050 750)(-5550 750);
WIRE 16 -1 (-5050 700)(-5550 700);
WIRE 16 -1 (-5050 650)(-5550 650);
WIRE 16 -1 (-5050 1000)(-5550 1000);
WIRE 16 -1 (-5050 950)(-5550 950);
WIRE 16 -1 (-5050 900)(-5550 900);
WIRE 16 -1 (-5050 850)(-5550 850);
WIRE 16 -1 (-5550 2000)(-5050 2000);
WIRE 16 -1 (-5550 1950)(-5050 1950);
WIRE 16 -1 (-5550 1900)(-5050 1900);
WIRE 16 -1 (-5050 1850)(-5550 1850);
WIRE 16 -1 (-5550 1800)(-5050 1800);
WIRE 16 -1 (-5050 1700)(-5550 1700);
WIRE 16 -1 (-5550 1650)(-5050 1650);
WIRE 16 -1 (-5550 1600)(-5050 1600);
WIRE 16 -1 (-5550 1550)(-5050 1550);
WIRE 16 -1 (-5050 1450)(-5550 1450);
WIRE 16 -1 (-5050 1400)(-5550 1400);
WIRE 16 -1 (-5050 1350)(-5550 1350);
WIRE 16 -1 (-5050 1300)(-5550 1300);
WIRE 16 -1 (-5050 1250)(-5550 1250);
WIRE 16 -1 (-5050 1200)(-5550 1200);
WIRE 16 -1 (-5050 1150)(-5550 1150);
WIRE 16 -1 (-5050 1100)(-5550 1100);
WIRE 16 -1 (-5050 550)(-6400 550);
FORCEPROP 2 LAST SIG_NAME M_A_C<2>
J 0
(-6350 560);
DISPLAY 0.617021 (-6350 560);
PAINT ORANGE (-6350 560);
WIRE 16 -1 (-5550 1750)(-5050 1750);
FORCENOTE
SKYLAKE - SKT0 - 3 OF 21
(-1600 150) 0;
DISPLAY LEFT (-1600 150);
DISPLAY 1.021277 (-1600 150);
PAINT RED (-1600 150);
FORCENOTE
ROOM=CPU0
(-7925 350) 0;
DISPLAY LEFT (-7925 350);
DISPLAY 1.382979 (-7925 350);
PAINT PURPLE (-7925 350);
FORCENOTE
BOM_COST=PROC_SOCKET
(-7925 225) 0;
DISPLAY LEFT (-7925 225);
DISPLAY 1.382979 (-7925 225);
PAINT PURPLE (-7925 225);
QUIT
